G04 ================== begin FILE IDENTIFICATION RECORD ==================*
G04 Layout Name:  D:/<user>/Wistron_project/16317-1/gbr/16317-1.brd*
G04 Film Name:    TMASK*
G04 File Format:  Gerber RS274X*
G04 File Origin:  Cadence Allegro 16.5-S056*
G04 Origin Date:  Fri Jun 09 15:52:54 2017*
G04 *
G04 Layer:  VIA CLASS/SOLDERMASK_TOP*
G04 Layer:  PIN/SOLDERMASK_TOP*
G04 Layer:  PACKAGE GEOMETRY/SOLDERMASK_TOP*
G04 Layer:  DRAWING FORMAT/LAYER_PCB_STORY*
G04 Layer:  DRAWING FORMAT/LAYER_SOLDER_T*
G04 Layer:  BOARD GEOMETRY/SOLDERMASK_TOP*
G04 *
G04 Offset:    (0.00 0.00)*
G04 Mirror:    No*
G04 Mode:      Positive*
G04 Rotation:  0*
G04 FullContactRelief:  No*
G04 UndefLineWidth:     6.00*
G04 ================== end FILE IDENTIFICATION RECORD ====================*
%FSLAX35Y35*MOIN*%
%IR0*IPPOS*OFA0.00000B0.00000*MIA0B0*SFA1.00000B1.00000*%
%AMMACRO33*
4,1,40,.017,-.013,
.017,.013,
.016939,.013695,
.016759,.014368,
.016464,.015,
.016064,.015571,
.015571,.016064,
.015,.016464,
.014368,.016759,
.013695,.016939,
.013,.017,
-.013,.017,
-.013695,.016939,
-.014368,.016759,
-.015,.016464,
-.015571,.016064,
-.016064,.015571,
-.016464,.015,
-.016759,.014368,
-.016939,.013695,
-.017,.013,
-.017,-.013,
-.016939,-.013695,
-.016759,-.014368,
-.016464,-.015,
-.016064,-.015571,
-.015571,-.016064,
-.015,-.016464,
-.014368,-.016759,
-.013695,-.016939,
-.013,-.017,
.013,-.017,
.013695,-.016939,
.014368,-.016759,
.015,-.016464,
.015571,-.016064,
.016064,-.015571,
.016464,-.015,
.016759,-.014368,
.016939,-.013695,
.017,-.013,
0.0*
%
%ADD33MACRO33*%
%AMMACRO31*
4,1,40,.013,.017,
-.013,.017,
-.013695,.016939,
-.014368,.016759,
-.015,.016464,
-.015571,.016064,
-.016064,.015571,
-.016464,.015,
-.016759,.014368,
-.016939,.013695,
-.017,.013,
-.017,-.013,
-.016939,-.013695,
-.016759,-.014368,
-.016464,-.015,
-.016064,-.015571,
-.015571,-.016064,
-.015,-.016464,
-.014368,-.016759,
-.013695,-.016939,
-.013,-.017,
.013,-.017,
.013695,-.016939,
.014368,-.016759,
.015,-.016464,
.015571,-.016064,
.016064,-.015571,
.016464,-.015,
.016759,-.014368,
.016939,-.013695,
.017,-.013,
.017,.013,
.016939,.013695,
.016759,.014368,
.016464,.015,
.016064,.015571,
.015571,.016064,
.015,.016464,
.014368,.016759,
.013695,.016939,
.013,.017,
0.0*
%
%ADD31MACRO31*%
%ADD70R,.055X.11*%
%ADD75R,.11X.055*%
%ADD101O,.115X.048*%
%ADD24C,.02*%
%ADD88R,.056X.14*%
%ADD87C,.03*%
%ADD86C,.022*%
%ADD72R,.08X.127*%
%ADD96R,.127X.08*%
%ADD50C,.032*%
%AMMACRO47*
4,1,40,-.007,.004,
-.007,-.004,
-.00697,-.004347,
-.006879,-.004684,
-.006732,-.005,
-.006532,-.005286,
-.006286,-.005532,
-.006,-.005732,
-.005684,-.005879,
-.005347,-.00597,
-.005,-.006,
.005,-.006,
.005347,-.00597,
.005684,-.005879,
.006,-.005732,
.006286,-.005532,
.006532,-.005286,
.006732,-.005,
.006879,-.004684,
.00697,-.004347,
.007,-.004,
.007,.004,
.00697,.004347,
.006879,.004684,
.006732,.005,
.006532,.005286,
.006286,.005532,
.006,.005732,
.005684,.005879,
.005347,.00597,
.005,.006,
-.005,.006,
-.005347,.00597,
-.005684,.005879,
-.006,.005732,
-.006286,.005532,
-.006532,.005286,
-.006732,.005,
-.006879,.004684,
-.00697,.004347,
-.007,.004,
0.0*
%
%ADD47MACRO47*%
%ADD43C,.05*%
%ADD77R,.096X.22*%
%ADD73C,.024*%
%ADD105R,.118X.047*%
%ADD79C,.016*%
%ADD53C,.053*%
%ADD25C,.026*%
%ADD10C,.08*%
%ADD97O,.048X.166*%
%ADD95R,.008X.037*%
%ADD94R,.037X.008*%
%ADD46C,.037*%
%ADD71C,.056*%
%ADD98C,.048*%
%ADD104R,.157X.067*%
%ADD23C,.086*%
%AMMACRO42*
4,1,40,.0225,-.007,
.022378,-.008389,
.022018,-.009736,
.021428,-.011,
.020628,-.012142,
.019642,-.013128,
.0185,-.013928,
.017236,-.014518,
.015889,-.014878,
.0145,-.015,
-.0145,-.015,
-.015889,-.014878,
-.017236,-.014518,
-.0185,-.013928,
-.019642,-.013128,
-.020628,-.012142,
-.021428,-.011,
-.022018,-.009736,
-.022378,-.008389,
-.0225,-.007,
-.0225,.007,
-.022378,.008389,
-.022018,.009736,
-.021428,.011,
-.020628,.012142,
-.019642,.013128,
-.0185,.013928,
-.017236,.014518,
-.015889,.014878,
-.0145,.015,
.0145,.015,
.015889,.014878,
.017236,.014518,
.0185,.013928,
.019642,.013128,
.020628,.012142,
.021428,.011,
.022018,.009736,
.022378,.008389,
.0225,.007,
.0225,-.007,
0.0*
%
%ADD42MACRO42*%
%AMMACRO93*
4,1,40,-.007,-.0225,
-.008389,-.022378,
-.009736,-.022018,
-.011,-.021428,
-.012142,-.020628,
-.013128,-.019642,
-.013928,-.0185,
-.014518,-.017236,
-.014878,-.015889,
-.015,-.0145,
-.015,.0145,
-.014878,.015889,
-.014518,.017236,
-.013928,.0185,
-.013128,.019642,
-.012142,.020628,
-.011,.021428,
-.009736,.022018,
-.008389,.022378,
-.007,.0225,
.007,.0225,
.008389,.022378,
.009736,.022018,
.011,.021428,
.012142,.020628,
.013128,.019642,
.013928,.0185,
.014518,.017236,
.014878,.015889,
.015,.0145,
.015,-.0145,
.014878,-.015889,
.014518,-.017236,
.013928,-.0185,
.013128,-.019642,
.012142,-.020628,
.011,-.021428,
.009736,-.022018,
.008389,-.022378,
.007,-.0225,
-.007,-.0225,
0.0*
%
%ADD93MACRO93*%
%ADD69C,.099*%
%AMMACRO16*
4,1,40,.011,-.007,
.011,.007,
.010939,.007695,
.010759,.008368,
.010464,.009,
.010064,.009571,
.009571,.010064,
.009,.010464,
.008368,.010759,
.007695,.010939,
.007,.011,
-.007,.011,
-.007695,.010939,
-.008368,.010759,
-.009,.010464,
-.009571,.010064,
-.010064,.009571,
-.010464,.009,
-.010759,.008368,
-.010939,.007695,
-.011,.007,
-.011,-.007,
-.010939,-.007695,
-.010759,-.008368,
-.010464,-.009,
-.010064,-.009571,
-.009571,-.010064,
-.009,-.010464,
-.008368,-.010759,
-.007695,-.010939,
-.007,-.011,
.007,-.011,
.007695,-.010939,
.008368,-.010759,
.009,-.010464,
.009571,-.010064,
.010064,-.009571,
.010464,-.009,
.010759,-.008368,
.010939,-.007695,
.011,-.007,
0.0*
%
%ADD16MACRO16*%
%AMMACRO14*
4,1,40,.007,.011,
-.007,.011,
-.007695,.010939,
-.008368,.010759,
-.009,.010464,
-.009571,.010064,
-.010064,.009571,
-.010464,.009,
-.010759,.008368,
-.010939,.007695,
-.011,.007,
-.011,-.007,
-.010939,-.007695,
-.010759,-.008368,
-.010464,-.009,
-.010064,-.009571,
-.009571,-.010064,
-.009,-.010464,
-.008368,-.010759,
-.007695,-.010939,
-.007,-.011,
.007,-.011,
.007695,-.010939,
.008368,-.010759,
.009,-.010464,
.009571,-.010064,
.010064,-.009571,
.010464,-.009,
.010759,-.008368,
.010939,-.007695,
.011,-.007,
.011,.007,
.010939,.007695,
.010759,.008368,
.010464,.009,
.010064,.009571,
.009571,.010064,
.009,.010464,
.008368,.010759,
.007695,.010939,
.007,.011,
0.0*
%
%ADD14MACRO14*%
%AMMACRO29*
4,1,40,-.012,.008,
-.012,-.008,
-.011939,-.008695,
-.011759,-.009368,
-.011464,-.01,
-.011064,-.010571,
-.010571,-.011064,
-.01,-.011464,
-.009368,-.011759,
-.008695,-.011939,
-.008,-.012,
.008,-.012,
.008695,-.011939,
.009368,-.011759,
.01,-.011464,
.010571,-.011064,
.011064,-.010571,
.011464,-.01,
.011759,-.009368,
.011939,-.008695,
.012,-.008,
.012,.008,
.011939,.008695,
.011759,.009368,
.011464,.01,
.011064,.010571,
.010571,.011064,
.01,.011464,
.009368,.011759,
.008695,.011939,
.008,.012,
-.008,.012,
-.008695,.011939,
-.009368,.011759,
-.01,.011464,
-.010571,.011064,
-.011064,.010571,
-.011464,.01,
-.011759,.009368,
-.011939,.008695,
-.012,.008,
0.0*
%
%ADD29MACRO29*%
%AMMACRO56*
4,1,40,.008,.012,
-.008,.012,
-.008695,.011939,
-.009368,.011759,
-.01,.011464,
-.010571,.011064,
-.011064,.010571,
-.011464,.01,
-.011759,.009368,
-.011939,.008695,
-.012,.008,
-.012,-.008,
-.011939,-.008695,
-.011759,-.009368,
-.011464,-.01,
-.011064,-.010571,
-.010571,-.011064,
-.01,-.011464,
-.009368,-.011759,
-.008695,-.011939,
-.008,-.012,
.008,-.012,
.008695,-.011939,
.009368,-.011759,
.01,-.011464,
.010571,-.011064,
.011064,-.010571,
.011464,-.01,
.011759,-.009368,
.011939,-.008695,
.012,-.008,
.012,.008,
.011939,.008695,
.011759,.009368,
.011464,.01,
.011064,.010571,
.010571,.011064,
.01,.011464,
.009368,.011759,
.008695,.011939,
.008,.012,
0.0*
%
%ADD56MACRO56*%
%AMMACRO48*
4,1,40,-.013,-.017,
.013,-.017,
.013695,-.016939,
.014368,-.016759,
.015,-.016464,
.015571,-.016064,
.016064,-.015571,
.016464,-.015,
.016759,-.014368,
.016939,-.013695,
.017,-.013,
.017,.013,
.016939,.013695,
.016759,.014368,
.016464,.015,
.016064,.015571,
.015571,.016064,
.015,.016464,
.014368,.016759,
.013695,.016939,
.013,.017,
-.013,.017,
-.013695,.016939,
-.014368,.016759,
-.015,.016464,
-.015571,.016064,
-.016064,.015571,
-.016464,.015,
-.016759,.014368,
-.016939,.013695,
-.017,.013,
-.017,-.013,
-.016939,-.013695,
-.016759,-.014368,
-.016464,-.015,
-.016064,-.015571,
-.015571,-.016064,
-.015,-.016464,
-.014368,-.016759,
-.013695,-.016939,
-.013,-.017,
0.0*
%
%ADD48MACRO48*%
%AMMACRO39*
4,1,40,-.017,.013,
-.017,-.013,
-.016939,-.013695,
-.016759,-.014368,
-.016464,-.015,
-.016064,-.015571,
-.015571,-.016064,
-.015,-.016464,
-.014368,-.016759,
-.013695,-.016939,
-.013,-.017,
.013,-.017,
.013695,-.016939,
.014368,-.016759,
.015,-.016464,
.015571,-.016064,
.016064,-.015571,
.016464,-.015,
.016759,-.014368,
.016939,-.013695,
.017,-.013,
.017,.013,
.016939,.013695,
.016759,.014368,
.016464,.015,
.016064,.015571,
.015571,.016064,
.015,.016464,
.014368,.016759,
.013695,.016939,
.013,.017,
-.013,.017,
-.013695,.016939,
-.014368,.016759,
-.015,.016464,
-.015571,.016064,
-.016064,.015571,
-.016464,.015,
-.016759,.014368,
-.016939,.013695,
-.017,.013,
0.0*
%
%ADD39MACRO39*%
%AMMACRO17*
4,1,40,.011,-.007,
.011,.007,
.010939,.007695,
.010759,.008368,
.010464,.009,
.010064,.009571,
.009571,.010064,
.009,.010464,
.008368,.010759,
.007695,.010939,
.007,.011,
-.007,.011,
-.007695,.010939,
-.008368,.010759,
-.009,.010464,
-.009571,.010064,
-.010064,.009571,
-.010464,.009,
-.010759,.008368,
-.010939,.007695,
-.011,.007,
-.011,-.007,
-.010939,-.007695,
-.010759,-.008368,
-.010464,-.009,
-.010064,-.009571,
-.009571,-.010064,
-.009,-.010464,
-.008368,-.010759,
-.007695,-.010939,
-.007,-.011,
.007,-.011,
.007695,-.010939,
.008368,-.010759,
.009,-.010464,
.009571,-.010064,
.010064,-.009571,
.010464,-.009,
.010759,-.008368,
.010939,-.007695,
.011,-.007,
0.0*
%
%ADD17MACRO17*%
%AMMACRO15*
4,1,40,.007,.011,
-.007,.011,
-.007695,.010939,
-.008368,.010759,
-.009,.010464,
-.009571,.010064,
-.010064,.009571,
-.010464,.009,
-.010759,.008368,
-.010939,.007695,
-.011,.007,
-.011,-.007,
-.010939,-.007695,
-.010759,-.008368,
-.010464,-.009,
-.010064,-.009571,
-.009571,-.010064,
-.009,-.010464,
-.008368,-.010759,
-.007695,-.010939,
-.007,-.011,
.007,-.011,
.007695,-.010939,
.008368,-.010759,
.009,-.010464,
.009571,-.010064,
.010064,-.009571,
.010464,-.009,
.010759,-.008368,
.010939,-.007695,
.011,-.007,
.011,.007,
.010939,.007695,
.010759,.008368,
.010464,.009,
.010064,.009571,
.009571,.010064,
.009,.010464,
.008368,.010759,
.007695,.010939,
.007,.011,
0.0*
%
%ADD15MACRO15*%
%AMMACRO28*
4,1,40,-.012,.008,
-.012,-.008,
-.011939,-.008695,
-.011759,-.009368,
-.011464,-.01,
-.011064,-.010571,
-.010571,-.011064,
-.01,-.011464,
-.009368,-.011759,
-.008695,-.011939,
-.008,-.012,
.008,-.012,
.008695,-.011939,
.009368,-.011759,
.01,-.011464,
.010571,-.011064,
.011064,-.010571,
.011464,-.01,
.011759,-.009368,
.011939,-.008695,
.012,-.008,
.012,.008,
.011939,.008695,
.011759,.009368,
.011464,.01,
.011064,.010571,
.010571,.011064,
.01,.011464,
.009368,.011759,
.008695,.011939,
.008,.012,
-.008,.012,
-.008695,.011939,
-.009368,.011759,
-.01,.011464,
-.010571,.011064,
-.011064,.010571,
-.011464,.01,
-.011759,.009368,
-.011939,.008695,
-.012,.008,
0.0*
%
%ADD28MACRO28*%
%AMMACRO55*
4,1,40,.008,.012,
-.008,.012,
-.008695,.011939,
-.009368,.011759,
-.01,.011464,
-.010571,.011064,
-.011064,.010571,
-.011464,.01,
-.011759,.009368,
-.011939,.008695,
-.012,.008,
-.012,-.008,
-.011939,-.008695,
-.011759,-.009368,
-.011464,-.01,
-.011064,-.010571,
-.010571,-.011064,
-.01,-.011464,
-.009368,-.011759,
-.008695,-.011939,
-.008,-.012,
.008,-.012,
.008695,-.011939,
.009368,-.011759,
.01,-.011464,
.010571,-.011064,
.011064,-.010571,
.011464,-.01,
.011759,-.009368,
.011939,-.008695,
.012,-.008,
.012,.008,
.011939,.008695,
.011759,.009368,
.011464,.01,
.011064,.010571,
.010571,.011064,
.01,.011464,
.009368,.011759,
.008695,.011939,
.008,.012,
0.0*
%
%ADD55MACRO55*%
%AMMACRO49*
4,1,40,-.013,-.017,
.013,-.017,
.013695,-.016939,
.014368,-.016759,
.015,-.016464,
.015571,-.016064,
.016064,-.015571,
.016464,-.015,
.016759,-.014368,
.016939,-.013695,
.017,-.013,
.017,.013,
.016939,.013695,
.016759,.014368,
.016464,.015,
.016064,.015571,
.015571,.016064,
.015,.016464,
.014368,.016759,
.013695,.016939,
.013,.017,
-.013,.017,
-.013695,.016939,
-.014368,.016759,
-.015,.016464,
-.015571,.016064,
-.016064,.015571,
-.016464,.015,
-.016759,.014368,
-.016939,.013695,
-.017,.013,
-.017,-.013,
-.016939,-.013695,
-.016759,-.014368,
-.016464,-.015,
-.016064,-.015571,
-.015571,-.016064,
-.015,-.016464,
-.014368,-.016759,
-.013695,-.016939,
-.013,-.017,
0.0*
%
%ADD49MACRO49*%
%AMMACRO40*
4,1,40,-.017,.013,
-.017,-.013,
-.016939,-.013695,
-.016759,-.014368,
-.016464,-.015,
-.016064,-.015571,
-.015571,-.016064,
-.015,-.016464,
-.014368,-.016759,
-.013695,-.016939,
-.013,-.017,
.013,-.017,
.013695,-.016939,
.014368,-.016759,
.015,-.016464,
.015571,-.016064,
.016064,-.015571,
.016464,-.015,
.016759,-.014368,
.016939,-.013695,
.017,-.013,
.017,.013,
.016939,.013695,
.016759,.014368,
.016464,.015,
.016064,.015571,
.015571,.016064,
.015,.016464,
.014368,.016759,
.013695,.016939,
.013,.017,
-.013,.017,
-.013695,.016939,
-.014368,.016759,
-.015,.016464,
-.015571,.016064,
-.016064,.015571,
-.016464,.015,
-.016759,.014368,
-.016939,.013695,
-.017,.013,
0.0*
%
%ADD40MACRO40*%
%ADD67R,.04X.022*%
%ADD103R,.02X.06*%
%ADD91R,.06X.03*%
%ADD21R,.022X.04*%
%ADD106R,.142X.106*%
%ADD84R,.012X.042*%
%ADD82R,.042X.012*%
%ADD89R,.06X.014*%
%ADD63R,.04X.016*%
%ADD61C,.101*%
%ADD66R,.032X.016*%
%ADD54C,.111*%
%ADD51R,.014X.06*%
%ADD22R,.016X.04*%
%ADD109R,.016X.032*%
%ADD92R,.06X.016*%
%ADD83R,.012X.036*%
%ADD81R,.036X.012*%
%AMMACRO107*
4,1,40,.007,-.004,
.007,.004,
.00697,.004347,
.006879,.004684,
.006732,.005,
.006532,.005286,
.006286,.005532,
.006,.005732,
.005684,.005879,
.005347,.00597,
.005,.006,
-.005,.006,
-.005347,.00597,
-.005684,.005879,
-.006,.005732,
-.006286,.005532,
-.006532,.005286,
-.006732,.005,
-.006879,.004684,
-.00697,.004347,
-.007,.004,
-.007,-.004,
-.00697,-.004347,
-.006879,-.004684,
-.006732,-.005,
-.006532,-.005286,
-.006286,-.005532,
-.006,-.005732,
-.005684,-.005879,
-.005347,-.00597,
-.005,-.006,
.005,-.006,
.005347,-.00597,
.005684,-.005879,
.006,-.005732,
.006286,-.005532,
.006532,-.005286,
.006732,-.005,
.006879,-.004684,
.00697,-.004347,
.007,-.004,
0.0*
%
%ADD107MACRO107*%
%ADD11R,.093X.02*%
%ADD34R,.05X.065*%
%ADD74C,.404*%
%ADD35R,.065X.05*%
%ADD108R,.065X.025*%
%ADD68C,.126*%
%ADD64R,.055X.035*%
%ADD44R,.093X.024*%
%ADD38R,.028X.034*%
%ADD76R,.035X.055*%
%ADD60R,.048X.016*%
%ADD45R,.102X.102*%
%ADD36R,.045X.055*%
%ADD20R,.025X.065*%
%ADD85R,.13X.13*%
%ADD65R,.016X.048*%
%ADD62C,.119*%
%ADD37R,.055X.045*%
%ADD102C,.138*%
%ADD90R,.073X.047*%
%AMMACRO100*
4,1,46,.00177,.018,
.003163,.017918,
.00452,.017595,
.0058,.017042,
.006965,.016274,
.007979,.015316,
.008812,.014196,
.009437,.012949,
.009836,.011613,
.009997,.010227,
.01,.01,
.01,-.01,
.00999,-.01,
.009868,-.011389,
.009507,-.012737,
.008918,-.014001,
.008118,-.015143,
.007132,-.016129,
.005989,-.016929,
.004725,-.017519,
.003378,-.01788,
.001989,-.018001,
.00185,-.018,
-.00185,-.018,
-.003241,-.017903,
-.004595,-.017565,
-.005869,-.016998,
-.007025,-.016218,
-.008028,-.015249,
-.008848,-.01412,
-.009459,-.012867,
-.009843,-.011526,
-.009989,-.010139,
-.00999,-.01,
-.01,-.01,
-.01,.01,
-.009878,.01139,
-.009517,.012737,
-.008928,.014002,
-.008128,.015144,
-.007141,.016131,
-.005998,.016931,
-.004734,.017521,
-.003387,.017882,
-.001997,.018003,
-.00177,.018,
.00177,.018,
0.0*
%
%ADD100MACRO100*%
%ADD99R,.09X.095*%
%AMMACRO80*
4,1,40,-.0225,.007,
-.022378,.008389,
-.022018,.009736,
-.021428,.011,
-.020628,.012142,
-.019642,.013128,
-.0185,.013928,
-.017236,.014518,
-.015889,.014878,
-.0145,.015,
.0145,.015,
.015889,.014878,
.017236,.014518,
.0185,.013928,
.019642,.013128,
.020628,.012142,
.021428,.011,
.022018,.009736,
.022378,.008389,
.0225,.007,
.0225,-.007,
.022378,-.008389,
.022018,-.009736,
.021428,-.011,
.020628,-.012142,
.019642,-.013128,
.0185,-.013928,
.017236,-.014518,
.015889,-.014878,
.0145,-.015,
-.0145,-.015,
-.015889,-.014878,
-.017236,-.014518,
-.0185,-.013928,
-.019642,-.013128,
-.020628,-.012142,
-.021428,-.011,
-.022018,-.009736,
-.022378,-.008389,
-.0225,-.007,
-.0225,.007,
0.0*
%
%ADD80MACRO80*%
%ADD78R,.096X.035*%
%ADD52C,.375*%
%AMMACRO41*
4,1,40,.007,.0225,
.008389,.022378,
.009736,.022018,
.011,.021428,
.012142,.020628,
.013128,.019642,
.013928,.0185,
.014518,.017236,
.014878,.015889,
.015,.0145,
.015,-.0145,
.014878,-.015889,
.014518,-.017236,
.013928,-.0185,
.013128,-.019642,
.012142,-.020628,
.011,-.021428,
.009736,-.022018,
.008389,-.022378,
.007,-.0225,
-.007,-.0225,
-.008389,-.022378,
-.009736,-.022018,
-.011,-.021428,
-.012142,-.020628,
-.013128,-.019642,
-.013928,-.0185,
-.014518,-.017236,
-.014878,-.015889,
-.015,-.0145,
-.015,.0145,
-.014878,.015889,
-.014518,.017236,
-.013928,.0185,
-.013128,.019642,
-.012142,.020628,
-.011,.021428,
-.009736,.022018,
-.008389,.022378,
-.007,.0225,
.007,.0225,
0.0*
%
%ADD41MACRO41*%
%ADD57O,.552X.788*%
%AMMACRO59*
4,1,40,-.008,-.012,
.008,-.012,
.008695,-.011939,
.009368,-.011759,
.01,-.011464,
.010571,-.011064,
.011064,-.010571,
.011464,-.01,
.011759,-.009368,
.011939,-.008695,
.012,-.008,
.012,.008,
.011939,.008695,
.011759,.009368,
.011464,.01,
.011064,.010571,
.010571,.011064,
.01,.011464,
.009368,.011759,
.008695,.011939,
.008,.012,
-.008,.012,
-.008695,.011939,
-.009368,.011759,
-.01,.011464,
-.010571,.011064,
-.011064,.010571,
-.011464,.01,
-.011759,.009368,
-.011939,.008695,
-.012,.008,
-.012,-.008,
-.011939,-.008695,
-.011759,-.009368,
-.011464,-.01,
-.011064,-.010571,
-.010571,-.011064,
-.01,-.011464,
-.009368,-.011759,
-.008695,-.011939,
-.008,-.012,
0.0*
%
%ADD59MACRO59*%
%AMMACRO27*
4,1,40,.012,-.008,
.012,.008,
.011939,.008695,
.011759,.009368,
.011464,.01,
.011064,.010571,
.010571,.011064,
.01,.011464,
.009368,.011759,
.008695,.011939,
.008,.012,
-.008,.012,
-.008695,.011939,
-.009368,.011759,
-.01,.011464,
-.010571,.011064,
-.011064,.010571,
-.011464,.01,
-.011759,.009368,
-.011939,.008695,
-.012,.008,
-.012,-.008,
-.011939,-.008695,
-.011759,-.009368,
-.011464,-.01,
-.011064,-.010571,
-.010571,-.011064,
-.01,-.011464,
-.009368,-.011759,
-.008695,-.011939,
-.008,-.012,
.008,-.012,
.008695,-.011939,
.009368,-.011759,
.01,-.011464,
.010571,-.011064,
.011064,-.010571,
.011464,-.01,
.011759,-.009368,
.011939,-.008695,
.012,-.008,
0.0*
%
%ADD27MACRO27*%
%AMMACRO12*
4,1,40,-.007,-.011,
.007,-.011,
.007695,-.010939,
.008368,-.010759,
.009,-.010464,
.009571,-.010064,
.010064,-.009571,
.010464,-.009,
.010759,-.008368,
.010939,-.007695,
.011,-.007,
.011,.007,
.010939,.007695,
.010759,.008368,
.010464,.009,
.010064,.009571,
.009571,.010064,
.009,.010464,
.008368,.010759,
.007695,.010939,
.007,.011,
-.007,.011,
-.007695,.010939,
-.008368,.010759,
-.009,.010464,
-.009571,.010064,
-.010064,.009571,
-.010464,.009,
-.010759,.008368,
-.010939,.007695,
-.011,.007,
-.011,-.007,
-.010939,-.007695,
-.010759,-.008368,
-.010464,-.009,
-.010064,-.009571,
-.009571,-.010064,
-.009,-.010464,
-.008368,-.010759,
-.007695,-.010939,
-.007,-.011,
0.0*
%
%ADD12MACRO12*%
%AMMACRO18*
4,1,40,-.011,.007,
-.011,-.007,
-.010939,-.007695,
-.010759,-.008368,
-.010464,-.009,
-.010064,-.009571,
-.009571,-.010064,
-.009,-.010464,
-.008368,-.010759,
-.007695,-.010939,
-.007,-.011,
.007,-.011,
.007695,-.010939,
.008368,-.010759,
.009,-.010464,
.009571,-.010064,
.010064,-.009571,
.010464,-.009,
.010759,-.008368,
.010939,-.007695,
.011,-.007,
.011,.007,
.010939,.007695,
.010759,.008368,
.010464,.009,
.010064,.009571,
.009571,.010064,
.009,.010464,
.008368,.010759,
.007695,.010939,
.007,.011,
-.007,.011,
-.007695,.010939,
-.008368,.010759,
-.009,.010464,
-.009571,.010064,
-.010064,.009571,
-.010464,.009,
-.010759,.008368,
-.010939,.007695,
-.011,.007,
0.0*
%
%ADD18MACRO18*%
%AMMACRO32*
4,1,40,.017,-.013,
.017,.013,
.016939,.013695,
.016759,.014368,
.016464,.015,
.016064,.015571,
.015571,.016064,
.015,.016464,
.014368,.016759,
.013695,.016939,
.013,.017,
-.013,.017,
-.013695,.016939,
-.014368,.016759,
-.015,.016464,
-.015571,.016064,
-.016064,.015571,
-.016464,.015,
-.016759,.014368,
-.016939,.013695,
-.017,.013,
-.017,-.013,
-.016939,-.013695,
-.016759,-.014368,
-.016464,-.015,
-.016064,-.015571,
-.015571,-.016064,
-.015,-.016464,
-.014368,-.016759,
-.013695,-.016939,
-.013,-.017,
.013,-.017,
.013695,-.016939,
.014368,-.016759,
.015,-.016464,
.015571,-.016064,
.016064,-.015571,
.016464,-.015,
.016759,-.014368,
.016939,-.013695,
.017,-.013,
0.0*
%
%ADD32MACRO32*%
%AMMACRO30*
4,1,40,.013,.017,
-.013,.017,
-.013695,.016939,
-.014368,.016759,
-.015,.016464,
-.015571,.016064,
-.016064,.015571,
-.016464,.015,
-.016759,.014368,
-.016939,.013695,
-.017,.013,
-.017,-.013,
-.016939,-.013695,
-.016759,-.014368,
-.016464,-.015,
-.016064,-.015571,
-.015571,-.016064,
-.015,-.016464,
-.014368,-.016759,
-.013695,-.016939,
-.013,-.017,
.013,-.017,
.013695,-.016939,
.014368,-.016759,
.015,-.016464,
.015571,-.016064,
.016064,-.015571,
.016464,-.015,
.016759,-.014368,
.016939,-.013695,
.017,-.013,
.017,.013,
.016939,.013695,
.016759,.014368,
.016464,.015,
.016064,.015571,
.015571,.016064,
.015,.016464,
.014368,.016759,
.013695,.016939,
.013,.017,
0.0*
%
%ADD30MACRO30*%
%AMMACRO58*
4,1,40,-.008,-.012,
.008,-.012,
.008695,-.011939,
.009368,-.011759,
.01,-.011464,
.010571,-.011064,
.011064,-.010571,
.011464,-.01,
.011759,-.009368,
.011939,-.008695,
.012,-.008,
.012,.008,
.011939,.008695,
.011759,.009368,
.011464,.01,
.011064,.010571,
.010571,.011064,
.01,.011464,
.009368,.011759,
.008695,.011939,
.008,.012,
-.008,.012,
-.008695,.011939,
-.009368,.011759,
-.01,.011464,
-.010571,.011064,
-.011064,.010571,
-.011464,.01,
-.011759,.009368,
-.011939,.008695,
-.012,.008,
-.012,-.008,
-.011939,-.008695,
-.011759,-.009368,
-.011464,-.01,
-.011064,-.010571,
-.010571,-.011064,
-.01,-.011464,
-.009368,-.011759,
-.008695,-.011939,
-.008,-.012,
0.0*
%
%ADD58MACRO58*%
%AMMACRO26*
4,1,40,.012,-.008,
.012,.008,
.011939,.008695,
.011759,.009368,
.011464,.01,
.011064,.010571,
.010571,.011064,
.01,.011464,
.009368,.011759,
.008695,.011939,
.008,.012,
-.008,.012,
-.008695,.011939,
-.009368,.011759,
-.01,.011464,
-.010571,.011064,
-.011064,.010571,
-.011464,.01,
-.011759,.009368,
-.011939,.008695,
-.012,.008,
-.012,-.008,
-.011939,-.008695,
-.011759,-.009368,
-.011464,-.01,
-.011064,-.010571,
-.010571,-.011064,
-.01,-.011464,
-.009368,-.011759,
-.008695,-.011939,
-.008,-.012,
.008,-.012,
.008695,-.011939,
.009368,-.011759,
.01,-.011464,
.010571,-.011064,
.011064,-.010571,
.011464,-.01,
.011759,-.009368,
.011939,-.008695,
.012,-.008,
0.0*
%
%ADD26MACRO26*%
%AMMACRO13*
4,1,40,-.007,-.011,
.007,-.011,
.007695,-.010939,
.008368,-.010759,
.009,-.010464,
.009571,-.010064,
.010064,-.009571,
.010464,-.009,
.010759,-.008368,
.010939,-.007695,
.011,-.007,
.011,.007,
.010939,.007695,
.010759,.008368,
.010464,.009,
.010064,.009571,
.009571,.010064,
.009,.010464,
.008368,.010759,
.007695,.010939,
.007,.011,
-.007,.011,
-.007695,.010939,
-.008368,.010759,
-.009,.010464,
-.009571,.010064,
-.010064,.009571,
-.010464,.009,
-.010759,.008368,
-.010939,.007695,
-.011,.007,
-.011,-.007,
-.010939,-.007695,
-.010759,-.008368,
-.010464,-.009,
-.010064,-.009571,
-.009571,-.010064,
-.009,-.010464,
-.008368,-.010759,
-.007695,-.010939,
-.007,-.011,
0.0*
%
%ADD13MACRO13*%
%AMMACRO19*
4,1,40,-.011,.007,
-.011,-.007,
-.010939,-.007695,
-.010759,-.008368,
-.010464,-.009,
-.010064,-.009571,
-.009571,-.010064,
-.009,-.010464,
-.008368,-.010759,
-.007695,-.010939,
-.007,-.011,
.007,-.011,
.007695,-.010939,
.008368,-.010759,
.009,-.010464,
.009571,-.010064,
.010064,-.009571,
.010464,-.009,
.010759,-.008368,
.010939,-.007695,
.011,-.007,
.011,.007,
.010939,.007695,
.010759,.008368,
.010464,.009,
.010064,.009571,
.009571,.010064,
.009,.010464,
.008368,.010759,
.007695,.010939,
.007,.011,
-.007,.011,
-.007695,.010939,
-.008368,.010759,
-.009,.010464,
-.009571,.010064,
-.010064,.009571,
-.010464,.009,
-.010759,.008368,
-.010939,.007695,
-.011,.007,
0.0*
%
%ADD19MACRO19*%
%ADD110C,.006*%
G75*
%LPD*%
G75*
G36*
G01X804631Y1322985D02*
X796031D01*
Y1313985D01*
X804631D01*
Y1322985D01*
G37*
G36*
G01Y1302185D02*
X796031D01*
Y1311185D01*
X804631D01*
Y1302185D01*
G37*
G36*
G01X793231Y1311185D02*
X784631D01*
Y1302185D01*
X793231D01*
Y1311185D01*
G37*
G36*
G01X784631Y1322985D02*
X793231D01*
Y1313985D01*
X784631D01*
Y1322985D01*
G37*
G36*
G01X805101Y1365491D02*
X796501D01*
Y1356491D01*
X805101D01*
Y1365491D01*
G37*
G36*
G01Y1344691D02*
X796501D01*
Y1353691D01*
X805101D01*
Y1344691D01*
G37*
G36*
G01X793701Y1353691D02*
X785101D01*
Y1344691D01*
X793701D01*
Y1353691D01*
G37*
G36*
G01X785101Y1365491D02*
X793701D01*
Y1356491D01*
X785101D01*
Y1365491D01*
G37*
G36*
G01X804880Y1403159D02*
X796280D01*
Y1394159D01*
X804880D01*
Y1403159D01*
G37*
G36*
G01Y1382359D02*
X796280D01*
Y1391359D01*
X804880D01*
Y1382359D01*
G37*
G36*
G01X793480Y1391359D02*
X784880D01*
Y1382359D01*
X793480D01*
Y1391359D01*
G37*
G36*
G01X784880Y1403159D02*
X793480D01*
Y1394159D01*
X784880D01*
Y1403159D01*
G37*
G36*
G01X1023118Y1330389D02*
X1014518D01*
Y1321389D01*
X1023118D01*
Y1330389D01*
G37*
G36*
G01Y1309589D02*
X1014518D01*
Y1318589D01*
X1023118D01*
Y1309589D01*
G37*
G36*
G01X1011718Y1318589D02*
X1003118D01*
Y1309589D01*
X1011718D01*
Y1318589D01*
G37*
G36*
G01X1003118Y1330389D02*
X1011718D01*
Y1321389D01*
X1003118D01*
Y1330389D01*
G37*
G36*
G01X1023118Y1385989D02*
X1014518D01*
Y1376989D01*
X1023118D01*
Y1385989D01*
G37*
G36*
G01Y1365189D02*
X1014518D01*
Y1374189D01*
X1023118D01*
Y1365189D01*
G37*
G36*
G01X1011718Y1374189D02*
X1003118D01*
Y1365189D01*
X1011718D01*
Y1374189D01*
G37*
G36*
G01X1003118Y1385989D02*
X1011718D01*
Y1376989D01*
X1003118D01*
Y1385989D01*
G37*
G36*
G01X1023118Y1358189D02*
X1014518D01*
Y1349189D01*
X1023118D01*
Y1358189D01*
G37*
G36*
G01Y1337389D02*
X1014518D01*
Y1346389D01*
X1023118D01*
Y1337389D01*
G37*
G36*
G01X1011718Y1346389D02*
X1003118D01*
Y1337389D01*
X1011718D01*
Y1346389D01*
G37*
G36*
G01X1003118Y1358189D02*
X1011718D01*
Y1349189D01*
X1003118D01*
Y1358189D01*
G37*
G54D100*
X1047000Y1425700D03*
X1049000Y1431300D03*
X1045000D03*
G54D110*
G01X489037Y-206331D02*
X489911Y-205456D01*
X490566Y-203998D01*
X491003Y-201955D01*
X490566Y-200206D01*
X489693Y-199039D01*
X488164Y-198164D01*
X482269D01*
Y-215664D01*
X489474D01*
X491003Y-214498D01*
X491876Y-212747D01*
X492313Y-210706D01*
X491876Y-208664D01*
X490566Y-206914D01*
X489037Y-206331D01*
X482269D01*
G01X501734Y-215664D02*
Y-203998D01*
G01Y-206331D02*
X502826Y-205164D01*
X503918Y-204289D01*
X505446Y-203998D01*
X506537Y-204289D01*
X507848Y-205164D01*
G01X517706Y-220914D02*
X519016Y-221497D01*
X520763Y-220914D01*
X521854Y-219748D01*
X522728Y-218289D01*
X524037Y-213623D01*
X526876Y-203998D01*
G01X519889D02*
X524037Y-213623D01*
G01X543284Y-205456D02*
X541756Y-204289D01*
X540446Y-203998D01*
X538699Y-204581D01*
X537389Y-205747D01*
X536516Y-207789D01*
X536297Y-209831D01*
X536516Y-211873D01*
X537389Y-213623D01*
X538699Y-215081D01*
X540446Y-215664D01*
X541974Y-215081D01*
X543284Y-213914D01*
G01X554016Y-207789D02*
X561003D01*
X560348Y-205747D01*
X559256Y-204581D01*
X557728Y-203998D01*
X556199Y-204289D01*
X554889Y-205164D01*
X554016Y-207206D01*
X553579Y-208956D01*
Y-210706D01*
X554016Y-212456D01*
X555108Y-214206D01*
X556418Y-215372D01*
X557946Y-215664D01*
X559474Y-215081D01*
X561003Y-213331D01*
G01X597094Y-199623D02*
X595784Y-198747D01*
X594256Y-198164D01*
X592509D01*
X590544Y-199039D01*
X589016Y-200497D01*
X587924Y-202248D01*
X587051Y-205164D01*
X586832Y-207789D01*
X587269Y-210414D01*
X587924Y-212164D01*
X589234Y-213914D01*
X590763Y-215081D01*
X592291Y-215664D01*
X593819D01*
X595348Y-215081D01*
X596658Y-214206D01*
X597750Y-213040D01*
G01X613721Y-215664D02*
Y-203998D01*
G01Y-206039D02*
X612848Y-204873D01*
X611537Y-204289D01*
X610009Y-203998D01*
X608481Y-204581D01*
X607171Y-205747D01*
X606297Y-207497D01*
X605861Y-209831D01*
X606297Y-212164D01*
X607171Y-213914D01*
X608481Y-215081D01*
X610009Y-215664D01*
X611537Y-215372D01*
X612848Y-214498D01*
X613721Y-213331D01*
G01X623579Y-215664D02*
Y-203998D01*
G01Y-206914D02*
X624453Y-205456D01*
X625763Y-204289D01*
X627509Y-203998D01*
X629037Y-204289D01*
X630348Y-205456D01*
X631003Y-207497D01*
Y-215664D01*
G01X640206Y-220914D02*
X641516Y-221497D01*
X643263Y-220914D01*
X644354Y-219748D01*
X645228Y-218289D01*
X646537Y-213623D01*
X649376Y-203998D01*
G01X642389D02*
X646537Y-213623D01*
G01X662291Y-215664D02*
X660981Y-215372D01*
X659671Y-214206D01*
X658797Y-212164D01*
X658361Y-209831D01*
X658797Y-207497D01*
X659671Y-205456D01*
X660981Y-204289D01*
X662291Y-203998D01*
X663601Y-204289D01*
X664911Y-205456D01*
X665784Y-207497D01*
X666003Y-209831D01*
X665784Y-212164D01*
X664911Y-214206D01*
X663601Y-215372D01*
X662291Y-215664D01*
G01X676079D02*
Y-203998D01*
G01Y-206914D02*
X676953Y-205456D01*
X678263Y-204289D01*
X680009Y-203998D01*
X681537Y-204289D01*
X682848Y-205456D01*
X683503Y-207497D01*
Y-215664D01*
G01X710424D02*
Y-198164D01*
X715883D01*
X717629Y-199039D01*
X718721Y-200206D01*
X719158Y-202539D01*
X718721Y-204873D01*
X717411Y-206331D01*
X715883Y-207206D01*
X710424D01*
G01X715883D02*
X719158Y-215664D01*
G01X732291Y-216247D02*
X731854Y-215956D01*
Y-215372D01*
X732291Y-215081D01*
X732728Y-215372D01*
Y-215956D01*
X732291Y-216247D01*
G01X744988Y-215664D02*
Y-198164D01*
X749354D01*
X751101Y-199039D01*
X752411Y-200206D01*
X753503Y-201955D01*
X754376Y-203998D01*
X754594Y-206914D01*
X754376Y-209831D01*
X753503Y-211873D01*
X752411Y-213623D01*
X751101Y-214789D01*
X749354Y-215664D01*
X744988D01*
G01X762924D02*
Y-198164D01*
X768164D01*
X769911Y-199039D01*
X771221Y-201081D01*
X771658Y-203414D01*
X771221Y-205747D01*
X770129Y-207497D01*
X768164Y-208373D01*
X762924D01*
G01X786537Y-206331D02*
X787411Y-205456D01*
X788066Y-203998D01*
X788503Y-201955D01*
X788066Y-200206D01*
X787193Y-199039D01*
X785664Y-198164D01*
X779769D01*
Y-215664D01*
X786974D01*
X788503Y-214498D01*
X789376Y-212747D01*
X789813Y-210706D01*
X789376Y-208664D01*
X788066Y-206914D01*
X786537Y-206331D01*
X779769D01*
G01X595364Y-170664D02*
Y-153164D01*
X601041Y-167747D01*
X606718Y-153164D01*
Y-170664D01*
G01X618541D02*
X617231Y-170372D01*
X615921Y-169206D01*
X615047Y-167164D01*
X614611Y-164831D01*
X615047Y-162497D01*
X615921Y-160456D01*
X617231Y-159289D01*
X618541Y-158998D01*
X619851Y-159289D01*
X621161Y-160456D01*
X622034Y-162497D01*
X622253Y-164831D01*
X622034Y-167164D01*
X621161Y-169206D01*
X619851Y-170372D01*
X618541Y-170664D01*
G01X639971Y-153164D02*
Y-170664D01*
G01Y-168040D02*
X639098Y-169498D01*
X637787Y-170372D01*
X636259Y-170664D01*
X634513Y-170081D01*
X633203Y-168623D01*
X632329Y-166873D01*
X632111Y-164831D01*
X632329Y-162789D01*
X633203Y-161039D01*
X634513Y-159581D01*
X636259Y-158998D01*
X637787Y-159289D01*
X638879Y-159873D01*
X639971Y-161039D01*
G01X650266Y-162789D02*
X657253D01*
X656598Y-160747D01*
X655506Y-159581D01*
X653978Y-158998D01*
X652449Y-159289D01*
X651139Y-160164D01*
X650266Y-162206D01*
X649829Y-163956D01*
Y-165706D01*
X650266Y-167456D01*
X651358Y-169206D01*
X652668Y-170372D01*
X654196Y-170664D01*
X655724Y-170081D01*
X657253Y-168331D01*
G01X671041Y-170664D02*
Y-153164D01*
G01X839441Y-215664D02*
Y-198164D01*
X836821Y-201664D01*
G01Y-215664D02*
X842061D01*
G01X852793Y-208373D02*
X854321Y-206331D01*
X855631Y-205164D01*
X857378Y-204581D01*
X858906Y-205164D01*
X859998Y-206331D01*
X860871Y-208081D01*
X861089Y-210122D01*
X860871Y-211873D01*
X859998Y-213623D01*
X858687Y-215081D01*
X857159Y-215664D01*
X855413Y-215081D01*
X853884Y-213331D01*
X853011Y-210706D01*
X852793Y-207789D01*
X853229Y-203998D01*
X853884Y-201955D01*
X854976Y-199914D01*
X856504Y-198456D01*
X858033Y-198164D01*
X859561Y-198747D01*
X860653Y-200206D01*
G01X869638Y-212164D02*
X870947Y-214206D01*
X872694Y-215372D01*
X874659Y-215664D01*
X876406Y-215372D01*
X878153Y-213914D01*
X879244Y-212164D01*
X879463Y-210414D01*
X879026Y-208373D01*
X877498Y-206914D01*
X875969Y-206331D01*
X874004D01*
G01X875969D02*
X877279Y-205456D01*
X878371Y-203998D01*
X878808Y-202248D01*
X878371Y-200497D01*
X877279Y-199039D01*
X875314Y-198164D01*
X873349Y-198456D01*
X871384Y-199623D01*
G01X891941Y-215664D02*
Y-198164D01*
X889321Y-201664D01*
G01Y-215664D02*
X894561D01*
G01X909004D02*
X909441Y-211873D01*
X910096Y-208664D01*
X910969Y-205747D01*
X912061Y-202539D01*
X913808Y-198164D01*
X905074D01*
G01X826324Y-170664D02*
Y-153164D01*
X831564D01*
X833311Y-154039D01*
X834621Y-156081D01*
X835058Y-158414D01*
X834621Y-160747D01*
X833529Y-162497D01*
X831564Y-163373D01*
X826324D01*
G01X852994Y-154623D02*
X851684Y-153747D01*
X850156Y-153164D01*
X848409D01*
X846444Y-154039D01*
X844916Y-155497D01*
X843824Y-157248D01*
X842951Y-160164D01*
X842732Y-162789D01*
X843169Y-165414D01*
X843824Y-167164D01*
X845134Y-168914D01*
X846663Y-170081D01*
X848191Y-170664D01*
X849719D01*
X851248Y-170081D01*
X852558Y-169206D01*
X853650Y-168040D01*
G01X867437Y-161331D02*
X868311Y-160456D01*
X868966Y-158998D01*
X869403Y-156955D01*
X868966Y-155206D01*
X868093Y-154039D01*
X866564Y-153164D01*
X860669D01*
Y-170664D01*
X867874D01*
X869403Y-169498D01*
X870276Y-167747D01*
X870713Y-165706D01*
X870276Y-163664D01*
X868966Y-161914D01*
X867437Y-161331D01*
X860669D01*
G01X876641Y-176497D02*
X889741D01*
G01X895669Y-170664D02*
Y-153164D01*
X905713Y-170664D01*
Y-153164D01*
G01X918191Y-170664D02*
X916444Y-170372D01*
X914916Y-169206D01*
X913606Y-167456D01*
X912732Y-165414D01*
X912296Y-163081D01*
Y-160747D01*
X912732Y-158414D01*
X913606Y-156372D01*
X914916Y-154623D01*
X916444Y-153456D01*
X918191Y-153164D01*
X919937Y-153456D01*
X921466Y-154623D01*
X922776Y-156372D01*
X923650Y-158414D01*
X924086Y-160747D01*
Y-163081D01*
X923650Y-165414D01*
X922776Y-167456D01*
X921466Y-169206D01*
X919937Y-170372D01*
X918191Y-170664D01*
G01X1000741Y-215664D02*
Y-198164D01*
X998121Y-201664D01*
G01Y-215664D02*
X1003361D01*
G01X969032Y-153164D02*
X974491Y-170664D01*
X979950Y-153164D01*
G01X996358Y-170664D02*
X987624D01*
Y-153164D01*
X996358D01*
G01X992864Y-161622D02*
X987624D01*
G01X1005124Y-170664D02*
Y-153164D01*
X1010583D01*
X1012329Y-154039D01*
X1013421Y-155206D01*
X1013858Y-157539D01*
X1013421Y-159873D01*
X1012111Y-161331D01*
X1010583Y-162206D01*
X1005124D01*
G01X1010583D02*
X1013858Y-170664D01*
G01X1026991Y-171247D02*
X1026554Y-170956D01*
Y-170372D01*
X1026991Y-170081D01*
X1027428Y-170372D01*
Y-170956D01*
X1026991Y-171247D01*
G01X1106941Y-198164D02*
Y-215664D01*
G01X1101919Y-198164D02*
X1111963D01*
G01X1118764Y-215664D02*
Y-198164D01*
X1124441Y-212747D01*
X1130118Y-198164D01*
Y-215664D01*
G01X1136482D02*
X1141941Y-198164D01*
X1147400Y-215664D01*
G01X1145434Y-209539D02*
X1138447D01*
G01X1154856Y-213331D02*
X1156603Y-214789D01*
X1158568Y-215664D01*
X1160314D01*
X1162061Y-214789D01*
X1163371Y-213331D01*
X1164026Y-211289D01*
X1163589Y-209248D01*
X1162498Y-207497D01*
X1160533Y-206331D01*
X1157913Y-205747D01*
X1156384Y-204581D01*
X1155729Y-202539D01*
X1156166Y-200497D01*
X1157258Y-199039D01*
X1158786Y-198164D01*
X1160314D01*
X1161843Y-198747D01*
X1163153Y-200206D01*
G01X1172138Y-215664D02*
Y-198164D01*
G01X1180434D02*
X1172138Y-208956D01*
G01X1181744Y-215664D02*
X1175849Y-203998D01*
G01X1102574Y-153164D02*
Y-170664D01*
X1111308D01*
G01X1128371D02*
Y-158998D01*
G01Y-161039D02*
X1127498Y-159873D01*
X1126187Y-159289D01*
X1124659Y-158998D01*
X1123131Y-159581D01*
X1121821Y-160747D01*
X1120947Y-162497D01*
X1120511Y-164831D01*
X1120947Y-167164D01*
X1121821Y-168914D01*
X1123131Y-170081D01*
X1124659Y-170664D01*
X1126187Y-170372D01*
X1127498Y-169498D01*
X1128371Y-168331D01*
G01X1137356Y-175914D02*
X1138666Y-176497D01*
X1140413Y-175914D01*
X1141504Y-174748D01*
X1142378Y-173289D01*
X1143687Y-168623D01*
X1146526Y-158998D01*
G01X1139539D02*
X1143687Y-168623D01*
G01X1156166Y-162789D02*
X1163153D01*
X1162498Y-160747D01*
X1161406Y-159581D01*
X1159878Y-158998D01*
X1158349Y-159289D01*
X1157039Y-160164D01*
X1156166Y-162206D01*
X1155729Y-163956D01*
Y-165706D01*
X1156166Y-167456D01*
X1157258Y-169206D01*
X1158568Y-170372D01*
X1160096Y-170664D01*
X1161624Y-170081D01*
X1163153Y-168331D01*
G01X1173884Y-170664D02*
Y-158998D01*
G01Y-161331D02*
X1174976Y-160164D01*
X1176068Y-159289D01*
X1177596Y-158998D01*
X1178687Y-159289D01*
X1179998Y-160164D01*
G01X1244688Y-170664D02*
Y-153164D01*
X1249054D01*
X1250801Y-154039D01*
X1252111Y-155206D01*
X1253203Y-156955D01*
X1254076Y-158998D01*
X1254294Y-161914D01*
X1254076Y-164831D01*
X1253203Y-166873D01*
X1252111Y-168623D01*
X1250801Y-169789D01*
X1249054Y-170664D01*
X1244688D01*
G01X1263716Y-162789D02*
X1270703D01*
X1270048Y-160747D01*
X1268956Y-159581D01*
X1267428Y-158998D01*
X1265899Y-159289D01*
X1264589Y-160164D01*
X1263716Y-162206D01*
X1263279Y-163956D01*
Y-165706D01*
X1263716Y-167456D01*
X1264808Y-169206D01*
X1266118Y-170372D01*
X1267646Y-170664D01*
X1269174Y-170081D01*
X1270703Y-168331D01*
G01X1281216Y-168623D02*
X1282308Y-169789D01*
X1283836Y-170664D01*
X1285146D01*
X1286456Y-170081D01*
X1287329Y-169206D01*
X1287766Y-168040D01*
X1287548Y-166289D01*
X1286674Y-165414D01*
X1282744Y-163664D01*
X1281871Y-161622D01*
X1282308Y-160164D01*
X1283181Y-159289D01*
X1284491Y-158998D01*
X1285801Y-159289D01*
X1287111Y-160164D01*
G01X1301991Y-158998D02*
Y-170664D01*
G01Y-154331D02*
X1301554Y-154039D01*
Y-153456D01*
X1301991Y-153164D01*
X1302428Y-153456D01*
Y-154039D01*
X1301991Y-154331D01*
G01X1316434Y-175039D02*
X1317963Y-176206D01*
X1319709Y-176497D01*
X1321237Y-176206D01*
X1322548Y-174748D01*
X1323421Y-172706D01*
Y-158998D01*
G01Y-161331D02*
X1322548Y-160164D01*
X1321237Y-159289D01*
X1319709Y-158998D01*
X1317963Y-159581D01*
X1316871Y-160747D01*
X1315997Y-162789D01*
X1315561Y-164831D01*
X1315779Y-166581D01*
X1316653Y-168623D01*
X1317963Y-170081D01*
X1319709Y-170664D01*
X1321019Y-170372D01*
X1322548Y-169206D01*
X1323421Y-168040D01*
G01X1333279Y-170664D02*
Y-158998D01*
G01Y-161914D02*
X1334153Y-160456D01*
X1335463Y-159289D01*
X1337209Y-158998D01*
X1338737Y-159289D01*
X1340048Y-160456D01*
X1340703Y-162497D01*
Y-170664D01*
G01X1351216Y-162789D02*
X1358203D01*
X1357548Y-160747D01*
X1356456Y-159581D01*
X1354928Y-158998D01*
X1353399Y-159289D01*
X1352089Y-160164D01*
X1351216Y-162206D01*
X1350779Y-163956D01*
Y-165706D01*
X1351216Y-167456D01*
X1352308Y-169206D01*
X1353618Y-170372D01*
X1355146Y-170664D01*
X1356674Y-170081D01*
X1358203Y-168331D01*
G01X1368934Y-170664D02*
Y-158998D01*
G01Y-161331D02*
X1370026Y-160164D01*
X1371118Y-159289D01*
X1372646Y-158998D01*
X1373737Y-159289D01*
X1375048Y-160164D01*
G01X1266991Y-215664D02*
X1265244Y-215372D01*
X1263716Y-214206D01*
X1262406Y-212456D01*
X1261532Y-210414D01*
X1261096Y-208081D01*
Y-205747D01*
X1261532Y-203414D01*
X1262406Y-201372D01*
X1263716Y-199623D01*
X1265244Y-198456D01*
X1266991Y-198164D01*
X1268737Y-198456D01*
X1270266Y-199623D01*
X1271576Y-201372D01*
X1272450Y-203414D01*
X1272886Y-205747D01*
Y-208081D01*
X1272450Y-210414D01*
X1271576Y-212456D01*
X1270266Y-214206D01*
X1268737Y-215372D01*
X1266991Y-215664D01*
G01X1268737Y-210997D02*
X1271358Y-215664D01*
G01X1279688Y-198164D02*
Y-210706D01*
X1280561Y-213331D01*
X1282308Y-215081D01*
X1284491Y-215664D01*
X1286674Y-215081D01*
X1288421Y-213331D01*
X1289294Y-210706D01*
Y-198164D01*
G01X1299371D02*
X1304611D01*
G01X1301991D02*
Y-215664D01*
G01X1299371D02*
X1304611D01*
G01X1314469D02*
Y-198164D01*
X1324513Y-215664D01*
Y-198164D01*
G01X1341794Y-199623D02*
X1340484Y-198747D01*
X1338956Y-198164D01*
X1337209D01*
X1335244Y-199039D01*
X1333716Y-200497D01*
X1332624Y-202248D01*
X1331751Y-205164D01*
X1331532Y-207789D01*
X1331969Y-210414D01*
X1332624Y-212164D01*
X1333934Y-213914D01*
X1335463Y-215081D01*
X1336991Y-215664D01*
X1338519D01*
X1340048Y-215081D01*
X1341358Y-214206D01*
X1342450Y-213040D01*
G01X1354491Y-215664D02*
Y-207789D01*
X1350124Y-198164D01*
G01X1358858D02*
X1354491Y-207789D01*
G01X1415691Y-198164D02*
X1413944Y-198747D01*
X1412634Y-200206D01*
X1411761Y-201955D01*
X1411106Y-204289D01*
X1410888Y-206914D01*
X1411106Y-209539D01*
X1411761Y-211873D01*
X1412634Y-213623D01*
X1413944Y-215081D01*
X1415691Y-215664D01*
X1417437Y-215081D01*
X1418748Y-213623D01*
X1419621Y-211873D01*
X1420276Y-209539D01*
X1420494Y-206914D01*
X1420276Y-204289D01*
X1419621Y-201955D01*
X1418748Y-200206D01*
X1417437Y-198747D01*
X1415691Y-198164D01*
G01X1429043Y-208373D02*
X1430571Y-206331D01*
X1431881Y-205164D01*
X1433628Y-204581D01*
X1435156Y-205164D01*
X1436248Y-206331D01*
X1437121Y-208081D01*
X1437339Y-210122D01*
X1437121Y-211873D01*
X1436248Y-213623D01*
X1434937Y-215081D01*
X1433409Y-215664D01*
X1431663Y-215081D01*
X1430134Y-213331D01*
X1429261Y-210706D01*
X1429043Y-207789D01*
X1429479Y-203998D01*
X1430134Y-201955D01*
X1431226Y-199914D01*
X1432754Y-198456D01*
X1434283Y-198164D01*
X1435811Y-198747D01*
X1436903Y-200206D01*
G01X1446761Y-216247D02*
X1454621Y-198164D01*
G01X1468191D02*
X1466444Y-198747D01*
X1465134Y-200206D01*
X1464261Y-201955D01*
X1463606Y-204289D01*
X1463388Y-206914D01*
X1463606Y-209539D01*
X1464261Y-211873D01*
X1465134Y-213623D01*
X1466444Y-215081D01*
X1468191Y-215664D01*
X1469937Y-215081D01*
X1471248Y-213623D01*
X1472121Y-211873D01*
X1472776Y-209539D01*
X1472994Y-206914D01*
X1472776Y-204289D01*
X1472121Y-201955D01*
X1471248Y-200206D01*
X1469937Y-198747D01*
X1468191Y-198164D01*
G01X1481979Y-213623D02*
X1483508Y-215081D01*
X1485254Y-215664D01*
X1487001Y-215081D01*
X1488529Y-213331D01*
X1489621Y-210706D01*
X1490058Y-208081D01*
Y-204873D01*
X1489621Y-202248D01*
X1488529Y-199914D01*
X1487219Y-198747D01*
X1485691Y-198164D01*
X1483944Y-198747D01*
X1482634Y-199914D01*
X1481761Y-201664D01*
X1481324Y-203998D01*
X1481761Y-206039D01*
X1482853Y-208081D01*
X1484163Y-209248D01*
X1485691Y-209539D01*
X1487437Y-208956D01*
X1488748Y-207497D01*
X1490058Y-204873D01*
G01X1499261Y-216247D02*
X1507121Y-198164D01*
G01X1516543Y-201081D02*
X1517853Y-199331D01*
X1519381Y-198456D01*
X1521128Y-198164D01*
X1523311Y-198747D01*
X1524839Y-200206D01*
X1525276Y-201955D01*
X1525058Y-203706D01*
X1524184Y-205164D01*
X1519818Y-208081D01*
X1517853Y-210122D01*
X1516543Y-213040D01*
X1516106Y-215664D01*
X1525276D01*
G01X1538191Y-198164D02*
X1536444Y-198747D01*
X1535134Y-200206D01*
X1534261Y-201955D01*
X1533606Y-204289D01*
X1533388Y-206914D01*
X1533606Y-209539D01*
X1534261Y-211873D01*
X1535134Y-213623D01*
X1536444Y-215081D01*
X1538191Y-215664D01*
X1539937Y-215081D01*
X1541248Y-213623D01*
X1542121Y-211873D01*
X1542776Y-209539D01*
X1542994Y-206914D01*
X1542776Y-204289D01*
X1542121Y-201955D01*
X1541248Y-200206D01*
X1539937Y-198747D01*
X1538191Y-198164D01*
G01X1555691Y-215664D02*
Y-198164D01*
X1553071Y-201664D01*
G01Y-215664D02*
X1558311D01*
G01X1572754D02*
X1573191Y-211873D01*
X1573846Y-208664D01*
X1574719Y-205747D01*
X1575811Y-202539D01*
X1577558Y-198164D01*
X1568824D01*
G01X1463388Y-170664D02*
Y-153164D01*
X1467754D01*
X1469501Y-154039D01*
X1470811Y-155206D01*
X1471903Y-156955D01*
X1472776Y-158998D01*
X1472994Y-161914D01*
X1472776Y-164831D01*
X1471903Y-166873D01*
X1470811Y-168623D01*
X1469501Y-169789D01*
X1467754Y-170664D01*
X1463388D01*
G01X1489621D02*
Y-158998D01*
G01Y-161039D02*
X1488748Y-159873D01*
X1487437Y-159289D01*
X1485909Y-158998D01*
X1484381Y-159581D01*
X1483071Y-160747D01*
X1482197Y-162497D01*
X1481761Y-164831D01*
X1482197Y-167164D01*
X1483071Y-168914D01*
X1484381Y-170081D01*
X1485909Y-170664D01*
X1487437Y-170372D01*
X1488748Y-169498D01*
X1489621Y-168331D01*
G01X1503191Y-153164D02*
Y-170664D01*
G01X1500134Y-158998D02*
X1506248D01*
G01X1517416Y-162789D02*
X1524403D01*
X1523748Y-160747D01*
X1522656Y-159581D01*
X1521128Y-158998D01*
X1519599Y-159289D01*
X1518289Y-160164D01*
X1517416Y-162206D01*
X1516979Y-163956D01*
Y-165706D01*
X1517416Y-167456D01*
X1518508Y-169206D01*
X1519818Y-170372D01*
X1521346Y-170664D01*
X1522874Y-170081D01*
X1524403Y-168331D01*
G54D101*
X1104752Y1120040D03*
X1122980D03*
X1104752Y1132638D03*
X1122980D03*
G54D102*
X1104528Y1162257D03*
G54D103*
X1104760Y1334815D03*
X1112240D03*
Y1343815D03*
X1108500D03*
X1104760D03*
G54D10*
X34900Y34200D03*
X40600Y1464400D03*
X1894200Y1471300D03*
G54D20*
X89000Y93500D03*
X84000D03*
X79000D03*
X74000D03*
Y113500D03*
X79000D03*
X84000D03*
X89000D03*
X51000Y131500D03*
X56000D03*
X61000D03*
X66000D03*
Y111500D03*
X61000D03*
X56000D03*
X51000D03*
X89000Y546000D03*
X84000D03*
X79000D03*
X74000D03*
Y566000D03*
X79000D03*
X84000D03*
X89000D03*
X66000Y564000D03*
X61000D03*
X56000D03*
X51000D03*
Y584000D03*
X56000D03*
X61000D03*
X66000D03*
X89000Y999000D03*
X84000D03*
X79000D03*
X74000D03*
Y1019000D03*
X79000D03*
X84000D03*
X89000D03*
X51000Y1037000D03*
X56000D03*
X61000D03*
X66000D03*
Y1017000D03*
X61000D03*
X56000D03*
X51000D03*
X188500Y86000D03*
X183500D03*
X178500D03*
X173500D03*
Y106000D03*
X178500D03*
X183500D03*
X188500D03*
X190000Y564000D03*
X185000D03*
X180000D03*
X175000D03*
Y584000D03*
X180000D03*
X185000D03*
X190000D03*
X175500Y1037000D03*
X180500D03*
X185500D03*
X190500D03*
Y1017000D03*
X185500D03*
X180500D03*
X175500D03*
X194174Y1430800D03*
Y1410800D03*
X213000Y93500D03*
X208000D03*
X203000D03*
X198000D03*
Y113500D03*
X203000D03*
X208000D03*
X213000D03*
Y546000D03*
X208000D03*
X203000D03*
X198000D03*
Y566000D03*
X203000D03*
X208000D03*
X213000D03*
X213500Y999000D03*
X208500D03*
X203500D03*
X198500D03*
Y1019000D03*
X203500D03*
X208500D03*
X213500D03*
X199174Y1430800D03*
X204174D03*
X209174D03*
Y1410800D03*
X204174D03*
X199174D03*
X337500Y93500D03*
X332500D03*
X327500D03*
X322500D03*
Y113500D03*
X327500D03*
X332500D03*
X337500D03*
X299500Y131500D03*
X304500D03*
X309500D03*
X314500D03*
Y111500D03*
X309500D03*
X304500D03*
X299500D03*
X337500Y546000D03*
X332500D03*
X327500D03*
X322500D03*
Y566000D03*
X327500D03*
X332500D03*
X337500D03*
X314500Y564000D03*
X309500D03*
X304500D03*
X299500D03*
Y584000D03*
X304500D03*
X309500D03*
X314500D03*
X337500Y999000D03*
X332500D03*
X327500D03*
X322500D03*
Y1019000D03*
X327500D03*
X332500D03*
X337500D03*
X299500Y1037000D03*
X304500D03*
X309500D03*
X314500D03*
Y1017000D03*
X309500D03*
X304500D03*
X299500D03*
X425500Y66600D03*
X430500D03*
X435500D03*
X440500D03*
Y46600D03*
X435500D03*
X430500D03*
X425500D03*
X461900Y97100D03*
X456900D03*
X451900D03*
X446900D03*
Y117100D03*
X451900D03*
X456900D03*
X461900D03*
X461500Y546000D03*
X456500D03*
X451500D03*
X446500D03*
Y566000D03*
X451500D03*
X456500D03*
X461500D03*
X438500Y564000D03*
X433500D03*
X428500D03*
X423500D03*
Y584000D03*
X428500D03*
X433500D03*
X438500D03*
X461500Y999000D03*
X456500D03*
X451500D03*
X446500D03*
Y1019000D03*
X451500D03*
X456500D03*
X461500D03*
X423500Y1037000D03*
X428500D03*
X433500D03*
X438500D03*
Y1017000D03*
X433500D03*
X428500D03*
X423500D03*
X576000Y93500D03*
X571000D03*
Y113500D03*
X576000D03*
X548000Y131500D03*
X553000D03*
X558000D03*
X563000D03*
Y111500D03*
X558000D03*
X553000D03*
X548000D03*
X576000Y546000D03*
X571000D03*
Y566000D03*
X576000D03*
X563000Y564000D03*
X558000D03*
X553000D03*
X548000D03*
Y584000D03*
X553000D03*
X558000D03*
X563000D03*
X576000Y999000D03*
X571000D03*
Y1019000D03*
X576000D03*
X548000Y1037000D03*
X553000D03*
X558000D03*
X563000D03*
Y1017000D03*
X558000D03*
X553000D03*
X548000D03*
X518035Y1418131D03*
X513035D03*
X508035D03*
X503035D03*
Y1438131D03*
X508035D03*
X513035D03*
X518035D03*
X586000Y93500D03*
X581000D03*
X670500Y86000D03*
X581000Y113500D03*
X586000D03*
X670500Y106000D03*
X586000Y546000D03*
X581000D03*
Y566000D03*
X586000D03*
X672000Y564000D03*
Y584000D03*
X586000Y999000D03*
X581000D03*
Y1019000D03*
X586000D03*
X672000Y1037000D03*
Y1017000D03*
X710000Y93500D03*
X705000D03*
X700000D03*
X695000D03*
X685500Y86000D03*
X680500D03*
X675500D03*
X695000Y113500D03*
X700000D03*
X705000D03*
X710000D03*
X675500Y106000D03*
X680500D03*
X685500D03*
X710000Y546000D03*
X705000D03*
X700000D03*
X695000D03*
Y566000D03*
X700000D03*
X705000D03*
X710000D03*
X687000Y564000D03*
X682000D03*
X677000D03*
Y584000D03*
X682000D03*
X687000D03*
X710000Y999000D03*
X705000D03*
X700000D03*
X695000D03*
Y1019000D03*
X700000D03*
X705000D03*
X710000D03*
X677000Y1037000D03*
X682000D03*
X687000D03*
Y1017000D03*
X682000D03*
X677000D03*
X989120Y845050D03*
X984120D03*
X979120D03*
X974120D03*
Y865050D03*
X979120D03*
X984120D03*
X989120D03*
X1220600Y1326833D03*
X1225600D03*
X1230600D03*
X1235600D03*
Y1306733D03*
X1230600D03*
X1225600D03*
X1220600D03*
X1187394Y1326833D03*
X1192394D03*
X1197394D03*
X1202394D03*
Y1306733D03*
X1197394D03*
X1192394D03*
X1187394D03*
X1314500Y82000D03*
X1309500D03*
X1304500D03*
X1299500D03*
Y102000D03*
X1304500D03*
X1309500D03*
X1314500D03*
X1318000Y140000D03*
X1323000D03*
X1328000D03*
X1333000D03*
Y120000D03*
X1328000D03*
X1323000D03*
X1318000D03*
X1333500Y573000D03*
X1328500D03*
X1323500D03*
X1318500D03*
Y593000D03*
X1323500D03*
X1328500D03*
X1333500D03*
X1318500Y1045500D03*
X1323500D03*
X1328500D03*
X1333500D03*
Y1025500D03*
X1328500D03*
X1323500D03*
X1318500D03*
X1333100Y1430700D03*
X1338100D03*
Y1410700D03*
X1333100D03*
X1343100Y1430700D03*
X1348100D03*
Y1410700D03*
X1343100D03*
X1442500Y140000D03*
X1447500D03*
X1452500D03*
X1457500D03*
Y120000D03*
X1452500D03*
X1447500D03*
X1442500D03*
X1457500Y573000D03*
X1452500D03*
X1447500D03*
X1442500D03*
Y593000D03*
X1447500D03*
X1452500D03*
X1457500D03*
X1442500Y1045500D03*
X1447500D03*
X1452500D03*
X1457500D03*
Y1025500D03*
X1452500D03*
X1447500D03*
X1442500D03*
X1564000Y82000D03*
X1559000D03*
X1554000D03*
X1549000D03*
Y102000D03*
X1554000D03*
X1559000D03*
X1564000D03*
X1582000Y573000D03*
X1577000D03*
X1572000D03*
X1567000D03*
Y593000D03*
X1572000D03*
X1577000D03*
X1582000D03*
X1567000Y1045500D03*
X1572000D03*
X1577000D03*
X1582000D03*
Y1025500D03*
X1577000D03*
X1572000D03*
X1567000D03*
X1691000Y140000D03*
X1696000D03*
X1701000D03*
X1706000D03*
Y120000D03*
X1701000D03*
X1696000D03*
X1691000D03*
X1706000Y573000D03*
X1701000D03*
X1696000D03*
X1691000D03*
Y593000D03*
X1696000D03*
X1701000D03*
X1706000D03*
X1691000Y1045500D03*
X1696000D03*
X1701000D03*
X1706000D03*
Y1025500D03*
X1701000D03*
X1696000D03*
X1691000D03*
X1721326Y1430600D03*
Y1410600D03*
X1811300Y91100D03*
X1806300D03*
X1801300D03*
X1796300D03*
Y111100D03*
X1801300D03*
X1806300D03*
X1811300D03*
X1814500Y140000D03*
Y120000D03*
X1815000Y573000D03*
Y593000D03*
Y1045500D03*
Y1025500D03*
X1726326Y1430600D03*
X1731326D03*
X1736326D03*
Y1410600D03*
X1731326D03*
X1726326D03*
X1880500Y93000D03*
X1875500D03*
X1870500D03*
X1865500D03*
X1856000Y85500D03*
X1851000D03*
X1846000D03*
X1841000D03*
X1865500Y113000D03*
X1870500D03*
X1875500D03*
X1880500D03*
X1819500Y140000D03*
X1824500D03*
X1829500D03*
Y120000D03*
X1824500D03*
X1819500D03*
X1841000Y105500D03*
X1846000D03*
X1851000D03*
X1856000D03*
X1880500Y546000D03*
X1875500D03*
X1870500D03*
X1865500D03*
Y566000D03*
X1870500D03*
X1875500D03*
X1880500D03*
X1830000Y573000D03*
X1825000D03*
X1820000D03*
X1857500Y564000D03*
X1852500D03*
X1847500D03*
X1842500D03*
X1820000Y593000D03*
X1825000D03*
X1830000D03*
X1842500Y584000D03*
X1847500D03*
X1852500D03*
X1857500D03*
X1880500Y999000D03*
X1875500D03*
X1870500D03*
X1865500D03*
Y1019000D03*
X1870500D03*
X1875500D03*
X1880500D03*
X1820000Y1045500D03*
X1825000D03*
X1830000D03*
Y1025500D03*
X1825000D03*
X1820000D03*
X1842500Y1037000D03*
X1847500D03*
X1852500D03*
X1857500D03*
Y1017000D03*
X1852500D03*
X1847500D03*
X1842500D03*
G54D11*
X99823Y93819D03*
Y90669D03*
Y87520D03*
Y84370D03*
Y103268D03*
Y100118D03*
Y96969D03*
Y556024D03*
Y552874D03*
Y549725D03*
Y546575D03*
Y543425D03*
Y540276D03*
Y537126D03*
Y1008780D03*
Y1005630D03*
Y1002481D03*
Y999331D03*
Y996181D03*
Y993032D03*
Y989882D03*
X224035Y93819D03*
Y90669D03*
Y87520D03*
Y84370D03*
Y103268D03*
Y100118D03*
Y96969D03*
Y556024D03*
Y552874D03*
Y549725D03*
Y546575D03*
Y543425D03*
Y540276D03*
Y537126D03*
Y1008780D03*
Y1005630D03*
Y1002481D03*
Y999331D03*
Y996181D03*
Y993032D03*
Y989882D03*
X348248Y93819D03*
Y90669D03*
Y87520D03*
Y84370D03*
Y103268D03*
Y100118D03*
Y96969D03*
Y556024D03*
Y552874D03*
Y549725D03*
Y546575D03*
Y543425D03*
Y540276D03*
Y537126D03*
Y1008780D03*
Y1005630D03*
Y1002481D03*
Y999331D03*
Y996181D03*
Y993032D03*
Y989882D03*
X472460Y93819D03*
Y90669D03*
Y87520D03*
Y84370D03*
Y103268D03*
Y100118D03*
Y96969D03*
Y556024D03*
Y552874D03*
Y549725D03*
Y546575D03*
Y543425D03*
Y540276D03*
Y537126D03*
Y1008780D03*
Y1005630D03*
Y1002481D03*
Y999331D03*
Y996181D03*
Y993032D03*
Y989882D03*
X596673Y93819D03*
Y90669D03*
Y87520D03*
Y84370D03*
Y103268D03*
Y100118D03*
Y96969D03*
Y556024D03*
Y552874D03*
Y549725D03*
Y546575D03*
Y543425D03*
Y540276D03*
Y537126D03*
Y1008780D03*
Y1005630D03*
Y1002481D03*
Y999331D03*
Y996181D03*
Y993032D03*
Y989882D03*
X720886Y93819D03*
Y90669D03*
Y87520D03*
Y84370D03*
Y103268D03*
Y100118D03*
Y96969D03*
Y556024D03*
Y552874D03*
Y549725D03*
Y546575D03*
Y543425D03*
Y540276D03*
Y537126D03*
Y1008780D03*
Y1005630D03*
Y1002481D03*
Y999331D03*
Y996181D03*
Y993032D03*
Y989882D03*
X1270492Y93819D03*
Y90669D03*
Y87520D03*
Y84370D03*
Y103268D03*
Y100118D03*
Y96969D03*
Y556024D03*
Y552874D03*
Y549725D03*
Y546575D03*
Y543425D03*
Y540276D03*
Y537126D03*
Y1008780D03*
Y1005630D03*
Y1002481D03*
Y999331D03*
Y996181D03*
Y993032D03*
Y989882D03*
X1394705Y93819D03*
Y90669D03*
Y87520D03*
Y84370D03*
Y103268D03*
Y100118D03*
Y96969D03*
Y556024D03*
Y552874D03*
Y549725D03*
Y546575D03*
Y543425D03*
Y540276D03*
Y537126D03*
Y1008780D03*
Y1005630D03*
Y1002481D03*
Y999331D03*
Y996181D03*
Y993032D03*
Y989882D03*
X1518917Y93819D03*
Y90669D03*
Y87520D03*
Y84370D03*
Y103268D03*
Y100118D03*
Y96969D03*
Y556024D03*
Y552874D03*
Y549725D03*
Y546575D03*
Y543425D03*
Y540276D03*
Y537126D03*
Y1008780D03*
Y1005630D03*
Y1002481D03*
Y999331D03*
Y996181D03*
Y993032D03*
Y989882D03*
X1643130Y93819D03*
Y90669D03*
Y87520D03*
Y84370D03*
Y103268D03*
Y100118D03*
Y96969D03*
Y556024D03*
Y552874D03*
Y549725D03*
Y546575D03*
Y543425D03*
Y540276D03*
Y537126D03*
Y1008780D03*
Y1005630D03*
Y1002481D03*
Y999331D03*
Y996181D03*
Y993032D03*
Y989882D03*
X1767342Y93819D03*
Y90669D03*
Y87520D03*
Y84370D03*
Y103268D03*
Y100118D03*
Y96969D03*
Y556024D03*
Y552874D03*
Y549725D03*
Y546575D03*
Y543425D03*
Y540276D03*
Y537126D03*
Y1008780D03*
Y1005630D03*
Y1002481D03*
Y999331D03*
Y996181D03*
Y993032D03*
Y989882D03*
X1891555Y93819D03*
Y90669D03*
Y87520D03*
Y84370D03*
Y103268D03*
Y100118D03*
Y96969D03*
Y556024D03*
Y552874D03*
Y549725D03*
Y546575D03*
Y543425D03*
Y540276D03*
Y537126D03*
Y1008780D03*
Y1005630D03*
Y1002481D03*
Y999331D03*
Y996181D03*
Y993032D03*
Y989882D03*
G54D104*
X1100000Y1493110D03*
Y1483268D03*
G54D30*
X76700Y133000D03*
X76600Y585500D03*
X94463Y903525D03*
X76500Y1038400D03*
X192290Y465789D03*
X139074Y1438500D03*
X201000Y133000D03*
Y585500D03*
X201100Y1038500D03*
X325300Y133000D03*
Y585500D03*
X325100Y1038500D03*
X449300Y133000D03*
X449600Y585500D03*
X449100Y1038500D03*
X573800Y133000D03*
X573700Y585500D03*
Y1038500D03*
X662200Y1448500D03*
X698000Y133000D03*
Y585500D03*
X697900Y1038500D03*
X861800Y779100D03*
X939200Y894000D03*
X966318Y534117D03*
X1010150Y842360D03*
X1026934Y1391632D03*
X969643Y1436399D03*
X1107200Y1327500D03*
X1109200Y1354000D03*
X1286074Y1438500D03*
X1666326D03*
X1735059Y469207D03*
X1757200Y595000D03*
X1809463Y903525D03*
X1872498Y68922D03*
X1868600Y132500D03*
X1868700Y585500D03*
X1868400Y1038500D03*
G54D12*
X67700Y91000D03*
X92200Y77000D03*
X60200Y65500D03*
X67700Y543500D03*
X92200Y529500D03*
X60200Y518000D03*
X89595Y905367D03*
X60200Y971000D03*
X92200Y982500D03*
X67700Y996500D03*
X187422Y467631D03*
X191700Y543500D03*
X184200Y518000D03*
X177008Y835918D03*
X184700Y971000D03*
X192200Y996500D03*
X188324Y1408800D03*
X117674Y1480400D03*
X129074Y1484200D03*
X218300Y57400D03*
X216200Y529500D03*
X216700Y982500D03*
X316200Y91000D03*
X340700Y77000D03*
X308700Y65500D03*
X316200Y543500D03*
X340700Y529500D03*
X308700Y518000D03*
Y971000D03*
X340700Y982500D03*
X316200Y996500D03*
X467200Y57500D03*
X440200Y543500D03*
X464700Y529500D03*
X432700Y518000D03*
Y971000D03*
X464700Y982500D03*
X440200Y996500D03*
X564700Y91000D03*
X557200Y65500D03*
X564700Y543500D03*
X557200Y518000D03*
Y971000D03*
X564700Y996500D03*
X510700Y1470500D03*
X528400Y1452100D03*
X528200Y1467000D03*
X589200Y77000D03*
Y529500D03*
Y982500D03*
X646895Y1425719D03*
X646995Y1441419D03*
X636200Y1464500D03*
X662000Y1468000D03*
X665200Y1444000D03*
X662000Y1464000D03*
Y1453500D03*
Y1457500D03*
X715700Y57400D03*
X688700Y543500D03*
X713200Y529500D03*
X681200Y518000D03*
Y971000D03*
X713200Y982500D03*
X688700Y996500D03*
X727200Y1453500D03*
X713700Y1443500D03*
X719700Y1458500D03*
Y1463000D03*
X684700Y1430000D03*
X692700D03*
X716700Y1438500D03*
X715800Y1475800D03*
X688200Y1476000D03*
X741432Y1466234D03*
X752932Y1465934D03*
X824690Y655190D03*
X818000Y772000D03*
Y781000D03*
X826200Y815000D03*
X827700Y893000D03*
X827587Y884453D03*
X946073Y556600D03*
X945788Y529107D03*
X946029Y551379D03*
X942927Y524023D03*
X874690Y647190D03*
Y655190D03*
X870500Y761000D03*
Y770000D03*
Y765500D03*
X878353Y807000D03*
X876200Y815000D03*
X912200Y782800D03*
X875700Y883000D03*
Y878500D03*
Y874000D03*
X933700Y875500D03*
X954438Y1412818D03*
Y1429318D03*
X963820Y770010D03*
Y774510D03*
X1029721Y830913D03*
X1004007Y903075D03*
X993597Y903465D03*
X1011481Y899075D03*
X1021739Y896965D03*
X1011200Y1117500D03*
X979200Y1201000D03*
Y1197000D03*
Y1209000D03*
Y1217000D03*
X1000143Y1417899D03*
X992143D03*
X1024143Y1426399D03*
X1021143Y1431399D03*
X1027143Y1451399D03*
Y1455899D03*
X1023950Y1496814D03*
X1045250Y1496914D03*
X972643Y1431899D03*
X968543Y1445399D03*
Y1441399D03*
X1057700Y824250D03*
Y814500D03*
Y837800D03*
Y828400D03*
X1078800Y1309495D03*
Y1304495D03*
Y1299375D03*
Y1292460D03*
X1105800Y1371200D03*
X1105812Y1391273D03*
X1105800Y1375200D03*
X1105812Y1383273D03*
X1196994Y918091D03*
X1196924Y912331D03*
X1210712Y1401814D03*
X1305000Y68900D03*
X1306800Y530000D03*
X1332700Y533500D03*
X1307800Y982200D03*
X1332700Y986000D03*
X1327350Y1408400D03*
X1263374Y1484900D03*
X1288074Y1480000D03*
X1274774Y1488600D03*
X1431300Y529900D03*
Y982400D03*
X1456700Y80500D03*
Y533500D03*
Y986000D03*
X1555400Y69300D03*
Y529800D03*
X1581200Y533500D03*
X1555700Y982600D03*
X1581200Y986000D03*
X1679600Y77000D03*
X1705200Y80500D03*
X1680000Y530100D03*
X1705200Y533500D03*
X1679600Y982300D03*
X1705200Y986000D03*
X1715576Y1408700D03*
X1656200Y1465000D03*
X1801100Y63200D03*
X1730191Y471049D03*
X1804000Y530100D03*
X1763200Y583500D03*
X1804595Y905367D03*
X1803700Y982200D03*
X1862500Y22300D03*
X1825600Y100800D03*
X1829200Y533500D03*
X1859200Y543500D03*
X1843200Y533500D03*
X1829200Y986000D03*
X1859200Y996500D03*
X1843200Y986500D03*
X1821226Y1470900D03*
G54D21*
X66500Y65000D03*
Y74000D03*
Y517500D03*
Y526500D03*
Y970500D03*
Y979500D03*
X190500Y517500D03*
Y526500D03*
X191000Y970500D03*
Y979500D03*
X174374Y1410900D03*
Y1401900D03*
X315000Y65000D03*
Y74000D03*
Y517500D03*
Y526500D03*
Y970500D03*
Y979500D03*
X439000Y517500D03*
Y526500D03*
Y970500D03*
Y979500D03*
X563500Y65000D03*
Y74000D03*
Y517500D03*
Y526500D03*
Y970500D03*
Y979500D03*
X687500Y517500D03*
Y526500D03*
Y970500D03*
Y979500D03*
X1317900Y59900D03*
Y68900D03*
X1313500Y1410900D03*
Y1401900D03*
X1570000Y60000D03*
Y69000D03*
X1701626Y1410900D03*
Y1401900D03*
X1868800Y22300D03*
Y31300D03*
X1849500Y533000D03*
Y542000D03*
Y986000D03*
Y995000D03*
G54D105*
X1060729Y1493189D03*
Y1483189D03*
G54D13*
X64300Y91000D03*
X88800Y77000D03*
X56800Y65500D03*
X64300Y543500D03*
X88800Y529500D03*
X56800Y518000D03*
X86195Y905367D03*
X56800Y971000D03*
X88800Y982500D03*
X64300Y996500D03*
X184022Y467631D03*
X188300Y543500D03*
X180800Y518000D03*
X173608Y835918D03*
X181300Y971000D03*
X188800Y996500D03*
X184924Y1408800D03*
X114274Y1480400D03*
X125674Y1484200D03*
X214900Y57400D03*
X212800Y529500D03*
X213300Y982500D03*
X312800Y91000D03*
X337300Y77000D03*
X305300Y65500D03*
X312800Y543500D03*
X337300Y529500D03*
X305300Y518000D03*
Y971000D03*
X337300Y982500D03*
X312800Y996500D03*
X463800Y57500D03*
X436800Y543500D03*
X461300Y529500D03*
X429300Y518000D03*
Y971000D03*
X461300Y982500D03*
X436800Y996500D03*
X561300Y91000D03*
X553800Y65500D03*
X561300Y543500D03*
X553800Y518000D03*
Y971000D03*
X561300Y996500D03*
X507300Y1470500D03*
X525000Y1452100D03*
X524800Y1467000D03*
X585800Y77000D03*
Y529500D03*
Y982500D03*
X643495Y1425719D03*
X643595Y1441419D03*
X632800Y1464500D03*
X658600Y1468000D03*
X661800Y1444000D03*
X658600Y1464000D03*
Y1453500D03*
Y1457500D03*
X712300Y57400D03*
X685300Y543500D03*
X709800Y529500D03*
X677800Y518000D03*
Y971000D03*
X709800Y982500D03*
X685300Y996500D03*
X723800Y1453500D03*
X710300Y1443500D03*
X716300Y1458500D03*
Y1463000D03*
X681300Y1430000D03*
X689300D03*
X713300Y1438500D03*
X712400Y1475800D03*
X684800Y1476000D03*
X738032Y1466234D03*
X749532Y1465934D03*
X821290Y655190D03*
X814600Y772000D03*
Y781000D03*
X822800Y815000D03*
X824300Y893000D03*
X824187Y884453D03*
X942673Y556600D03*
X942388Y529107D03*
X942629Y551379D03*
X939527Y524023D03*
X871290Y647190D03*
Y655190D03*
X867100Y761000D03*
Y770000D03*
Y765500D03*
X874953Y807000D03*
X872800Y815000D03*
X908800Y782800D03*
X872300Y883000D03*
Y878500D03*
Y874000D03*
X930300Y875500D03*
X951038Y1412818D03*
Y1429318D03*
X960420Y770010D03*
Y774510D03*
X1054300Y824250D03*
Y814500D03*
Y837800D03*
Y828400D03*
X1026321Y830913D03*
X1000607Y903075D03*
X990197Y903465D03*
X1008081Y899075D03*
X1018339Y896965D03*
X1007800Y1117500D03*
X975800Y1201000D03*
Y1197000D03*
Y1209000D03*
Y1217000D03*
X996743Y1417899D03*
X988743D03*
X1020743Y1426399D03*
X1017743Y1431399D03*
X1023743Y1451399D03*
Y1455899D03*
X1020550Y1496814D03*
X1041850Y1496914D03*
X969243Y1431899D03*
X965143Y1445399D03*
Y1441399D03*
X1075400Y1309495D03*
Y1304495D03*
Y1299375D03*
Y1292460D03*
X1102400Y1371200D03*
X1102412Y1391273D03*
X1102400Y1375200D03*
X1102412Y1383273D03*
X1193594Y918091D03*
X1193524Y912331D03*
X1207312Y1401814D03*
X1301600Y68900D03*
X1303400Y530000D03*
X1329300Y533500D03*
X1304400Y982200D03*
X1329300Y986000D03*
X1323950Y1408400D03*
X1259974Y1484900D03*
X1284674Y1480000D03*
X1271374Y1488600D03*
X1427900Y529900D03*
Y982400D03*
X1453300Y80500D03*
Y533500D03*
Y986000D03*
X1552000Y69300D03*
Y529800D03*
X1577800Y533500D03*
X1552300Y982600D03*
X1577800Y986000D03*
X1676200Y77000D03*
X1701800Y80500D03*
X1676600Y530100D03*
X1701800Y533500D03*
X1676200Y982300D03*
X1701800Y986000D03*
X1712176Y1408700D03*
X1652800Y1465000D03*
X1797700Y63200D03*
X1726791Y471049D03*
X1800600Y530100D03*
X1759800Y583500D03*
X1801195Y905367D03*
X1800300Y982200D03*
X1859100Y22300D03*
X1822200Y100800D03*
X1825800Y533500D03*
X1855800Y543500D03*
X1839800Y533500D03*
X1825800Y986000D03*
X1855800Y996500D03*
X1839800Y986500D03*
X1817826Y1470900D03*
G54D22*
X83060Y80700D03*
X80500D03*
X77940D03*
Y73300D03*
X80500D03*
X83060D03*
Y533200D03*
X80500D03*
X77940D03*
Y525800D03*
X80500D03*
X83060D03*
Y986200D03*
X80500D03*
X77940D03*
Y978800D03*
X80500D03*
X83060D03*
X207060Y533200D03*
X204500D03*
X201940D03*
Y525800D03*
X204500D03*
X207060D03*
X207560Y986200D03*
X205000D03*
X202440D03*
Y978800D03*
X205000D03*
X207560D03*
X331560Y80700D03*
X329000D03*
X326440D03*
Y73300D03*
X329000D03*
X331560D03*
Y533200D03*
X329000D03*
X326440D03*
Y525800D03*
X329000D03*
X331560D03*
Y986200D03*
X329000D03*
X326440D03*
Y978800D03*
X329000D03*
X331560D03*
X455560Y533200D03*
X453000D03*
X450440D03*
Y525800D03*
X453000D03*
X455560D03*
Y986200D03*
X453000D03*
X450440D03*
Y978800D03*
X453000D03*
X455560D03*
X574940Y80700D03*
Y73300D03*
Y533200D03*
Y525800D03*
Y986200D03*
Y978800D03*
X580060Y80700D03*
X577500D03*
Y73300D03*
X580060D03*
Y533200D03*
X577500D03*
Y525800D03*
X580060D03*
Y986200D03*
X577500D03*
Y978800D03*
X580060D03*
X704060Y533200D03*
X701500D03*
X698940D03*
Y525800D03*
X701500D03*
X704060D03*
Y986200D03*
X701500D03*
X698940D03*
Y978800D03*
X701500D03*
X704060D03*
X1801796Y1484390D03*
X1799236D03*
X1796676D03*
Y1476990D03*
X1799236D03*
X1801796D03*
X1886060Y36700D03*
X1883500D03*
X1880940D03*
Y29300D03*
X1883500D03*
X1886060D03*
G54D106*
X1228100Y1316783D03*
X1194894D03*
G54D40*
X79567Y394146D03*
X84567D03*
X73500Y846300D03*
X68500D03*
X95263Y885925D03*
X193090Y448189D03*
X191000Y846300D03*
X196000D03*
X213200Y393800D03*
X218200D03*
X315500D03*
X320500D03*
X315500Y846300D03*
X320500D03*
X440000Y393800D03*
X445000D03*
Y846300D03*
X440000D03*
X564000Y393800D03*
X569000D03*
X564000Y846300D03*
X569000D03*
X651295Y1441219D03*
X680500Y393800D03*
X685500D03*
X680500Y846300D03*
X685500D03*
X676500Y1429300D03*
X958738Y1429118D03*
X998000Y1119800D03*
X983943Y1417199D03*
X1040127Y1432300D03*
X1243500Y389300D03*
X1238462Y841988D03*
X1243462D03*
X1248500Y389300D03*
X1362500Y393300D03*
X1367500D03*
X1377100Y579000D03*
X1362500Y846800D03*
X1367500D03*
X1376900Y1031600D03*
X1487000Y393300D03*
X1492000D03*
X1500800Y578600D03*
X1487000Y846300D03*
X1492000D03*
X1500700Y1031600D03*
X1611000Y393300D03*
X1616000D03*
X1625500Y578800D03*
X1611000Y846300D03*
X1616000D03*
X1625400Y1031700D03*
X1735859Y451607D03*
X1735000Y393300D03*
X1740000D03*
X1735000Y846300D03*
X1740000D03*
X1810263Y885925D03*
X1749300Y1031700D03*
X1832100Y394100D03*
X1827100D03*
X1876100Y521000D03*
X1859500Y846300D03*
X1864500D03*
X1867500Y988000D03*
G54D31*
X82300Y133000D03*
X82200Y585500D03*
X100063Y903525D03*
X82100Y1038400D03*
X144674Y1438500D03*
X206600Y133000D03*
X197890Y465789D03*
X206600Y585500D03*
X206700Y1038500D03*
X330900Y133000D03*
Y585500D03*
X330700Y1038500D03*
X454900Y133000D03*
X455200Y585500D03*
X454700Y1038500D03*
X579400Y133000D03*
X579300Y585500D03*
Y1038500D03*
X667800Y1448500D03*
X703600Y133000D03*
Y585500D03*
X703500Y1038500D03*
X867400Y779100D03*
X944800Y894000D03*
X971918Y534117D03*
X1015750Y842360D03*
X1032534Y1391632D03*
X975243Y1436399D03*
X1112800Y1327500D03*
X1114800Y1354000D03*
X1291674Y1438500D03*
X1671926D03*
X1740659Y469207D03*
X1762800Y595000D03*
X1815063Y903525D03*
X1878098Y68922D03*
X1874200Y132500D03*
X1874300Y585500D03*
X1874000Y1038500D03*
G54D32*
X95500Y181800D03*
Y634300D03*
Y1087300D03*
X140500Y131900D03*
X219500Y181800D03*
X265000Y132000D03*
X219500Y634300D03*
X220000Y1087300D03*
X344000Y181800D03*
Y634300D03*
Y1087300D03*
X468000Y181800D03*
X389000Y132200D03*
X468000Y634300D03*
Y1087300D03*
X513600Y132100D03*
X528334Y1433529D03*
X528200Y1462400D03*
X592500Y181800D03*
X637300Y132100D03*
X592500Y634300D03*
Y1087300D03*
X651295Y1430719D03*
X716500Y181800D03*
X748400Y142900D03*
X716500Y634300D03*
X752500Y593800D03*
X716500Y1087300D03*
X752500Y1054300D03*
X838470Y942230D03*
X958738Y1418618D03*
X1131215Y1315870D03*
X1213033Y1313744D03*
X1180009Y1313953D03*
X1298500Y151800D03*
Y181300D03*
X1253000Y132200D03*
X1298500Y604800D03*
Y634300D03*
X1252800Y584900D03*
Y1037500D03*
X1298500Y1057300D03*
Y1086800D03*
X1422500Y151800D03*
Y181300D03*
X1376700Y132200D03*
X1422500Y604800D03*
Y634300D03*
Y1057300D03*
Y1086800D03*
X1501300Y132200D03*
X1547000Y151800D03*
Y181300D03*
X1625300Y132200D03*
X1547000Y604800D03*
Y634300D03*
Y1057300D03*
Y1086800D03*
X1671000Y151800D03*
Y181300D03*
Y604800D03*
Y634300D03*
Y1057300D03*
Y1086800D03*
X1795000Y151800D03*
Y181300D03*
X1749700Y131700D03*
X1795000Y604800D03*
Y634300D03*
Y1057300D03*
Y1086800D03*
X1887000Y181300D03*
Y634300D03*
Y1087300D03*
G54D41*
X69567Y389096D03*
X73442Y396596D03*
X65692D03*
X57300Y841750D03*
X61175Y849250D03*
X53425D03*
X180300Y841750D03*
X184175Y849250D03*
X176425D03*
X171374Y1421750D03*
X175249Y1429250D03*
X167499D03*
X203700Y388850D03*
X207575Y396350D03*
X199825D03*
X305400Y389050D03*
X309275Y396550D03*
X301525D03*
X305400Y841750D03*
X309275Y849250D03*
X301525D03*
X429900Y388850D03*
X433775Y396350D03*
X426025D03*
X429600Y841550D03*
X433475Y849050D03*
X425725D03*
X554100Y389050D03*
X557975Y396550D03*
X550225D03*
X665100Y388850D03*
X668975Y396350D03*
X661225D03*
X593680Y842750D03*
X597555Y850250D03*
X589805D03*
X670500Y841550D03*
X666625Y849050D03*
X674375D03*
X934000Y862250D03*
X937875Y869750D03*
X930125D03*
X1016000Y910750D03*
X1019875Y918250D03*
X1012125D03*
X1028050Y1479564D03*
X1024175Y1487064D03*
X1031925D03*
X1031163Y1464391D03*
X1035038Y1471891D03*
X1027288D03*
X1227969Y841750D03*
X1231844Y849250D03*
X1224094D03*
X1209846Y1407553D03*
X1213721Y1415053D03*
X1205971D03*
X1273803Y388837D03*
X1277678Y396337D03*
X1269928D03*
X1310500Y1421750D03*
X1314375Y1429250D03*
X1306625D03*
X1352182Y388994D03*
X1356057Y396494D03*
X1348307D03*
X1352182Y841750D03*
X1356057Y849250D03*
X1348307D03*
X1476394Y388994D03*
X1480269Y396494D03*
X1472519D03*
X1476394Y841750D03*
X1480269Y849250D03*
X1472519D03*
X1600607Y388994D03*
X1604482Y396494D03*
X1596732D03*
X1600607Y841750D03*
X1604482Y849250D03*
X1596732D03*
X1720944D03*
X1698626Y1421750D03*
X1702501Y1429250D03*
X1694751D03*
X1763791Y388797D03*
X1767666Y396297D03*
X1759916D03*
X1816000Y389350D03*
X1812125Y396850D03*
X1749634Y388793D03*
X1753509Y396293D03*
X1745759D03*
X1724819Y841750D03*
X1728694Y849250D03*
X1819875Y396850D03*
X1849032Y841750D03*
X1852907Y849250D03*
X1845157D03*
G54D107*
X1267378Y57719D03*
X1265178D03*
X1267378Y59919D03*
X1265178D03*
X1267378Y510475D03*
X1265178D03*
X1267378Y512675D03*
X1265178D03*
X1267378Y963231D03*
X1265178D03*
X1267378Y965431D03*
X1265178D03*
X1391591Y57719D03*
X1389391D03*
X1391591Y59919D03*
X1389391D03*
X1391591Y510475D03*
X1389391D03*
X1391591Y512675D03*
X1389391D03*
X1391591Y963231D03*
X1389391D03*
X1391591Y965431D03*
X1389391D03*
X1515803Y57719D03*
X1513603D03*
X1515803Y59919D03*
X1513603D03*
X1515803Y510475D03*
X1513603D03*
X1515803Y512675D03*
X1513603D03*
X1515803Y963231D03*
X1513603D03*
X1515803Y965431D03*
X1513603D03*
X1640016Y59919D03*
X1637816D03*
X1640016Y57719D03*
X1637816D03*
X1640016Y512675D03*
X1637816D03*
X1640016Y510475D03*
X1637816D03*
X1640016Y963231D03*
X1637816D03*
X1640016Y965431D03*
X1637816D03*
X1764228Y57719D03*
X1762028D03*
X1764228Y59919D03*
X1762028D03*
X1764228Y510475D03*
X1762028D03*
X1764228Y512675D03*
X1762028D03*
X1764228Y963231D03*
X1762028D03*
X1764228Y965431D03*
X1762028D03*
X1888441Y57719D03*
X1886241D03*
X1888441Y59919D03*
X1886241D03*
X1888441Y510475D03*
X1886241D03*
X1888441Y512675D03*
X1886241D03*
X1888441Y963231D03*
X1886241D03*
X1888441Y965431D03*
X1886241D03*
G54D14*
X88800Y72400D03*
X85600Y62800D03*
X56800Y96500D03*
X55259Y383528D03*
X69992Y403305D03*
X88600Y525300D03*
X86900Y516800D03*
X56800Y549000D03*
X42992Y836182D03*
X57725Y855959D03*
X94563Y908025D03*
X93655Y899023D03*
X86197Y901301D03*
X71363Y909325D03*
X70063Y892025D03*
X56800Y1002000D03*
X88800Y968000D03*
Y972500D03*
X195300Y78500D03*
X160800Y25100D03*
X157100Y32100D03*
X172200Y25100D03*
X160800Y21100D03*
X172200Y20900D03*
X168400Y29200D03*
X144100Y44400D03*
Y48500D03*
X192390Y470289D03*
X191482Y461287D03*
X184024Y463565D03*
X169190Y471589D03*
X167890Y454289D03*
X189392Y383182D03*
X180800Y549000D03*
X137300Y583000D03*
X180725Y855659D03*
X106363Y911925D03*
X106322Y903550D03*
X137300Y1036000D03*
X181300Y1002000D03*
X137774Y1472900D03*
X138674Y1452500D03*
Y1434000D03*
X124874Y1479100D03*
X203800Y45100D03*
X204190Y474189D03*
X204149Y465814D03*
X204125Y402959D03*
X212700Y525200D03*
X211200Y516600D03*
X261300Y583000D03*
X210900Y969700D03*
X213300Y978100D03*
X261000Y1036000D03*
X337200Y72600D03*
X335000Y63700D03*
X305300Y96500D03*
X291092Y383482D03*
X305825Y403259D03*
X337300Y525300D03*
X335100Y516800D03*
X305300Y549000D03*
X385800Y583000D03*
X291092Y836182D03*
X305825Y855959D03*
X305300Y1002000D03*
X334800Y969400D03*
X337200Y978200D03*
X385800Y1036000D03*
X452000Y44500D03*
X415592Y383182D03*
X430325Y402959D03*
X461300Y525300D03*
X459400Y516900D03*
X429300Y549000D03*
X415292Y835876D03*
X430025Y855659D03*
X429300Y1002000D03*
X459200Y969200D03*
X461200Y978000D03*
X553800Y96500D03*
X539792Y383482D03*
X554525Y403259D03*
X553800Y549000D03*
X509800Y583000D03*
Y1036000D03*
X553800Y1002000D03*
X585700Y72800D03*
X583800Y64300D03*
X650792Y383182D03*
X665525Y402959D03*
X585700Y525400D03*
X634300Y583000D03*
X656192Y835882D03*
X670925Y855659D03*
X579198Y836405D03*
X594105Y856859D03*
X583100Y969500D03*
X585800Y978100D03*
X634300Y1036000D03*
X668300Y1430000D03*
X692300Y78500D03*
X701300Y45050D03*
X748300Y130500D03*
X709700Y525300D03*
X677800Y549000D03*
Y1002000D03*
X707500Y969600D03*
X709900Y978300D03*
X749700Y1036000D03*
X710800Y1453500D03*
X712100Y1467300D03*
X723800Y1449000D03*
X712200Y1471600D03*
X821290Y659190D03*
Y647190D03*
Y651190D03*
X814600Y776500D03*
X814500Y785500D03*
X814600Y767500D03*
X822800Y819000D03*
Y807000D03*
Y811000D03*
X824300Y897500D03*
Y888500D03*
X824187Y880256D03*
X871290Y643190D03*
Y651190D03*
X867100Y756500D03*
X874953Y811000D03*
X872800Y803000D03*
X916100Y764800D03*
X908800Y774000D03*
Y778000D03*
X872300Y869500D03*
X954800Y898500D03*
X940800D03*
X955350Y1403400D03*
Y1399400D03*
X989548Y539555D03*
X991738Y517437D03*
X996141Y552081D03*
X991763Y526457D03*
X960420Y761010D03*
Y779010D03*
Y765510D03*
X1034181Y855984D03*
X1020300Y842500D03*
X1034184Y851705D03*
X1026462Y849214D03*
X1029642Y825127D03*
X1000607Y899075D03*
X990197Y895065D03*
X1008081Y903075D03*
X1018339Y900965D03*
X1024074Y939306D03*
X975800Y1225000D03*
Y1205000D03*
Y1221000D03*
Y1213000D03*
X975743Y1418699D03*
X1034150Y1496914D03*
X1020550Y1492814D03*
X1041850D03*
X1034150D03*
X1126800Y1291700D03*
Y1296700D03*
X1102412Y1379273D03*
Y1399273D03*
Y1395273D03*
Y1387273D03*
X1111800Y1358500D03*
X1213661Y836182D03*
X1228394Y855959D03*
X1184800Y892600D03*
Y886000D03*
Y906100D03*
Y899500D03*
X1330800Y109500D03*
X1337874Y383426D03*
X1259495Y383269D03*
X1274228Y403046D03*
X1331800Y562500D03*
X1337874Y836182D03*
X1331800Y1015000D03*
X1284674Y1471500D03*
X1285674Y1452500D03*
Y1434000D03*
X1271389Y1483400D03*
X1432300Y77000D03*
X1352607Y403203D03*
Y855959D03*
X1455800Y109500D03*
X1462086Y383426D03*
X1476819Y403203D03*
X1455800Y562500D03*
X1462086Y836182D03*
X1476819Y855959D03*
X1455800Y1015000D03*
X1601200Y129000D03*
X1586299Y383426D03*
X1601032Y403203D03*
X1580300Y562500D03*
X1586299Y836182D03*
X1601032Y855959D03*
X1580300Y1015000D03*
X1704300Y109500D03*
X1711959Y475007D03*
X1710659Y457707D03*
X1704300Y562500D03*
X1710511Y836182D03*
X1704300Y1015000D03*
X1665926Y1452500D03*
Y1434000D03*
X1812800Y64400D03*
X1735159Y473707D03*
X1746918Y469232D03*
X1734251Y464705D03*
X1726793Y466983D03*
X1801692Y383782D03*
X1816425Y403559D03*
X1749992Y402630D03*
X1764201Y402301D03*
X1746959Y477607D03*
X1725244Y855959D03*
X1809563Y908025D03*
X1808655Y899023D03*
X1801197Y901301D03*
X1786363Y909325D03*
X1785063Y892025D03*
X1803441Y1490100D03*
X1806411Y1471000D03*
X1818978Y85039D03*
Y80939D03*
X1878300Y77500D03*
X1862800Y78000D03*
X1864000Y38100D03*
X1821900Y32000D03*
X1827500Y25100D03*
Y20900D03*
X1835000Y29300D03*
X1838900Y25200D03*
Y21100D03*
X1827300Y109500D03*
X1828300Y562500D03*
X1876200Y530600D03*
X1848300Y549000D03*
X1849800Y527000D03*
X1834724Y836182D03*
X1849457Y855959D03*
X1821363Y911925D03*
X1821322Y903550D03*
X1828300Y1015000D03*
X1848300Y1002000D03*
X1849800Y980000D03*
G54D23*
X59400Y32600D03*
X63374Y1454500D03*
X390757Y1511515D03*
X812347Y17406D03*
X885639Y1511515D03*
X1187163Y158305D03*
X1538001Y1511515D03*
X1869500Y1461500D03*
G54D50*
X149300Y37300D03*
X136866Y156319D03*
Y609075D03*
X116263Y911525D03*
X136866Y1061831D03*
X261078Y156319D03*
X214090Y473789D03*
X261078Y609075D03*
Y1061831D03*
X385291Y156319D03*
Y609075D03*
Y1061831D03*
X509503Y156319D03*
Y609075D03*
Y1061831D03*
X633716Y156319D03*
Y609075D03*
Y1061831D03*
X708200Y148900D03*
X757929Y609075D03*
Y1061831D03*
X1020061Y847967D03*
X1256756Y156319D03*
Y609075D03*
Y1061831D03*
X1380969Y156319D03*
Y609075D03*
Y1061831D03*
X1505181Y156319D03*
Y609075D03*
Y1061831D03*
X1629394Y156319D03*
Y609075D03*
Y1061831D03*
X1812800Y38200D03*
X1753606Y156319D03*
X1756859Y477207D03*
X1753606Y609075D03*
Y1061831D03*
X1878100Y149600D03*
X1878200Y602900D03*
X1831263Y911525D03*
X1878300Y1056100D03*
G54D60*
X145445Y1425760D03*
Y1423200D03*
Y1420640D03*
X151945D03*
Y1425760D03*
G54D108*
X1328500Y554500D03*
Y549500D03*
Y544500D03*
Y539500D03*
X1308500D03*
Y544500D03*
Y549500D03*
Y554500D03*
X1328500Y1007000D03*
Y1002000D03*
Y997000D03*
Y992000D03*
X1308500D03*
Y997000D03*
Y1002000D03*
Y1007000D03*
X1432500Y86500D03*
Y91500D03*
Y96500D03*
Y101500D03*
Y539500D03*
Y544500D03*
Y549500D03*
Y554500D03*
Y992000D03*
Y997000D03*
Y1002000D03*
Y1007000D03*
X1452500Y91500D03*
Y86500D03*
Y101500D03*
Y96500D03*
Y554500D03*
Y549500D03*
Y544500D03*
Y539500D03*
Y1007000D03*
Y1002000D03*
Y997000D03*
Y992000D03*
X1570400Y126000D03*
Y131000D03*
Y136000D03*
Y141000D03*
X1590400D03*
Y136000D03*
Y131000D03*
Y126000D03*
X1577000Y554500D03*
Y549500D03*
Y544500D03*
Y539500D03*
X1557000D03*
Y544500D03*
Y549500D03*
Y554500D03*
X1577000Y1007000D03*
Y1002000D03*
Y997000D03*
Y992000D03*
X1557000D03*
Y997000D03*
Y1002000D03*
Y1007000D03*
X1701000Y91500D03*
Y86500D03*
X1681000D03*
Y91500D03*
X1701000Y101500D03*
Y96500D03*
X1681000D03*
Y101500D03*
X1701000Y554500D03*
Y549500D03*
Y544500D03*
Y539500D03*
X1681000D03*
Y544500D03*
Y549500D03*
Y554500D03*
X1701000Y1007000D03*
Y1002000D03*
Y997000D03*
Y992000D03*
X1681000D03*
Y997000D03*
Y1002000D03*
Y1007000D03*
X1805000Y539500D03*
Y544500D03*
Y549500D03*
Y554500D03*
Y992000D03*
Y997000D03*
Y1002000D03*
Y1007000D03*
X1825000Y554500D03*
Y549500D03*
Y544500D03*
Y539500D03*
Y1007000D03*
Y1002000D03*
Y997000D03*
Y992000D03*
G54D51*
X137501Y24706D03*
X134941D03*
X132381D03*
X129821D03*
Y40886D03*
X132381D03*
X134941D03*
X137501D03*
X799390Y940330D03*
X801950D03*
X804510D03*
X807070D03*
X809630D03*
X812190D03*
X814750D03*
X817310D03*
X819870D03*
X822430D03*
X824990D03*
X827550D03*
Y962530D03*
X824990D03*
X822430D03*
X819870D03*
X817310D03*
X814750D03*
X812190D03*
X809630D03*
X807070D03*
X804510D03*
X801950D03*
X799390D03*
X917620Y902564D03*
X915060D03*
X912500D03*
X909940D03*
X907380D03*
X904820D03*
X902260D03*
X899700D03*
X897140D03*
X894580D03*
X892020D03*
X889460D03*
Y880364D03*
X892020D03*
X894580D03*
X897140D03*
X899700D03*
X902260D03*
X904820D03*
X907380D03*
X909940D03*
X912500D03*
X915060D03*
X917620D03*
X946310Y861030D03*
X948870D03*
X951430D03*
X953990D03*
X956550D03*
Y883230D03*
X953990D03*
X951430D03*
X948870D03*
X946310D03*
X1002940Y856130D03*
X1005500D03*
X1008060D03*
X1010620D03*
X1013180D03*
X1015740D03*
X1018300D03*
X1020860D03*
X959110Y861030D03*
X961670D03*
X964230D03*
Y883230D03*
X961670D03*
X959110D03*
X1020860Y878330D03*
X1018300D03*
X1015740D03*
X1013180D03*
X1010620D03*
X1008060D03*
X1005500D03*
X1002940D03*
X1805021Y23406D03*
X1802461D03*
X1799901D03*
X1797341D03*
Y39586D03*
X1799901D03*
X1802461D03*
X1805021D03*
G54D15*
X92200Y72400D03*
X89000Y62800D03*
X60200Y96500D03*
X58659Y383528D03*
X73392Y403305D03*
X92000Y525300D03*
X90300Y516800D03*
X60200Y549000D03*
X46392Y836182D03*
X61125Y855959D03*
X97963Y908025D03*
X97055Y899023D03*
X89597Y901301D03*
X74763Y909325D03*
X73463Y892025D03*
X60200Y1002000D03*
X92200Y968000D03*
Y972500D03*
X164200Y25100D03*
X160500Y32100D03*
X175600Y25100D03*
X164200Y21100D03*
X175600Y20900D03*
X171800Y29200D03*
X147500Y44400D03*
Y48500D03*
X194882Y461287D03*
X187424Y463565D03*
X172590Y471589D03*
X171290Y454289D03*
X192792Y383182D03*
X184200Y549000D03*
X140700Y583000D03*
X184125Y855659D03*
X109763Y911925D03*
X109722Y903550D03*
X140700Y1036000D03*
X184700Y1002000D03*
X141174Y1472900D03*
X142074Y1452500D03*
Y1434000D03*
X128274Y1479100D03*
X198700Y78500D03*
X207200Y45100D03*
X207590Y474189D03*
X195790Y470289D03*
X207549Y465814D03*
X207525Y402959D03*
X216100Y525200D03*
X214600Y516600D03*
X264700Y583000D03*
X214300Y969700D03*
X216700Y978100D03*
X264400Y1036000D03*
X340600Y72600D03*
X338400Y63700D03*
X308700Y96500D03*
X294492Y383482D03*
X309225Y403259D03*
X340700Y525300D03*
X338500Y516800D03*
X308700Y549000D03*
X294492Y836182D03*
X309225Y855959D03*
X308700Y1002000D03*
X338200Y969400D03*
X340600Y978200D03*
X455400Y44500D03*
X418992Y383182D03*
X433725Y402959D03*
X464700Y525300D03*
X462800Y516900D03*
X432700Y549000D03*
X389200Y583000D03*
X418692Y835876D03*
X433425Y855659D03*
X389200Y1036000D03*
X432700Y1002000D03*
X462600Y969200D03*
X464600Y978000D03*
X557200Y96500D03*
X543192Y383482D03*
X557925Y403259D03*
X557200Y549000D03*
X513200Y583000D03*
Y1036000D03*
X557200Y1002000D03*
X589100Y72800D03*
X587200Y64300D03*
X654192Y383182D03*
X668925Y402959D03*
X589100Y525400D03*
X637700Y583000D03*
X659592Y835882D03*
X582598Y836405D03*
X597505Y856859D03*
X586500Y969500D03*
X589200Y978100D03*
X637700Y1036000D03*
X671700Y1430000D03*
X695700Y78500D03*
X704700Y45050D03*
X751700Y130500D03*
X713100Y525300D03*
X681200Y549000D03*
X674325Y855659D03*
X681200Y1002000D03*
X710900Y969600D03*
X713300Y978300D03*
X753100Y1036000D03*
X714200Y1453500D03*
X715500Y1467300D03*
X727200Y1449000D03*
X715600Y1471600D03*
X824690Y659190D03*
Y647190D03*
Y651190D03*
X818000Y776500D03*
X817900Y785500D03*
X818000Y767500D03*
X826200Y819000D03*
Y807000D03*
Y811000D03*
X827700Y897500D03*
Y888500D03*
X827587Y880256D03*
X874690Y643190D03*
Y651190D03*
X870500Y756500D03*
X878353Y811000D03*
X876200Y803000D03*
X919500Y764800D03*
X912200Y774000D03*
Y778000D03*
X875700Y869500D03*
X958200Y898500D03*
X944200D03*
X958750Y1403400D03*
Y1399400D03*
X992948Y539555D03*
X995138Y517437D03*
X999541Y552081D03*
X995163Y526457D03*
X963820Y761010D03*
Y779010D03*
Y765510D03*
X1037581Y855984D03*
X1023700Y842500D03*
X1037584Y851705D03*
X1029862Y849214D03*
X1033042Y825127D03*
X1004007Y899075D03*
X993597Y895065D03*
X1011481Y903075D03*
X1021739Y900965D03*
X1027474Y939306D03*
X979200Y1225000D03*
Y1205000D03*
Y1221000D03*
Y1213000D03*
X979143Y1418699D03*
X1037550Y1496914D03*
X1023950Y1492814D03*
X1045250D03*
X1037550D03*
X1130200Y1291700D03*
Y1296700D03*
X1105812Y1379273D03*
Y1399273D03*
Y1395273D03*
Y1387273D03*
X1115200Y1358500D03*
X1217061Y836182D03*
X1231794Y855959D03*
X1188200Y892600D03*
Y886000D03*
Y906100D03*
Y899500D03*
X1334200Y109500D03*
X1262895Y383269D03*
X1277628Y403046D03*
X1335200Y562500D03*
Y1015000D03*
X1288074Y1471500D03*
X1289074Y1452500D03*
Y1434000D03*
X1274789Y1483400D03*
X1435700Y77000D03*
X1341274Y383426D03*
X1356007Y403203D03*
X1341274Y836182D03*
X1356007Y855959D03*
X1459200Y109500D03*
X1465486Y383426D03*
X1480219Y403203D03*
X1459200Y562500D03*
X1465486Y836182D03*
X1480219Y855959D03*
X1459200Y1015000D03*
X1604600Y129000D03*
X1589699Y383426D03*
X1604432Y403203D03*
X1583700Y562500D03*
X1589699Y836182D03*
X1604432Y855959D03*
X1583700Y1015000D03*
X1707700Y109500D03*
X1715359Y475007D03*
X1714059Y457707D03*
X1707700Y562500D03*
X1713911Y836182D03*
X1707700Y1015000D03*
X1669326Y1452500D03*
Y1434000D03*
X1816200Y64400D03*
X1738559Y473707D03*
X1750318Y469232D03*
X1737651Y464705D03*
X1730193Y466983D03*
X1805092Y383782D03*
X1753392Y402630D03*
X1767601Y402301D03*
X1750359Y477607D03*
X1728644Y855959D03*
X1812963Y908025D03*
X1812055Y899023D03*
X1804597Y901301D03*
X1789763Y909325D03*
X1788463Y892025D03*
X1806841Y1490100D03*
X1809811Y1471000D03*
X1822378Y85039D03*
Y80939D03*
X1881700Y77500D03*
X1866200Y78000D03*
X1867400Y38100D03*
X1825300Y32000D03*
X1830900Y25100D03*
Y20900D03*
X1838400Y29300D03*
X1842300Y25200D03*
Y21100D03*
X1830700Y109500D03*
X1819825Y403559D03*
X1831700Y562500D03*
X1879600Y530600D03*
X1851700Y549000D03*
X1853200Y527000D03*
X1838124Y836182D03*
X1852857Y855959D03*
X1824763Y911925D03*
X1824722Y903550D03*
X1831700Y1015000D03*
X1851700Y1002000D03*
X1853200Y980000D03*
G54D42*
X51209Y393253D03*
X58709Y389378D03*
Y397128D03*
X38942Y845907D03*
X46442Y842032D03*
Y849782D03*
X185342Y392907D03*
X192842Y389032D03*
Y396782D03*
X160342Y840907D03*
X167842Y837032D03*
Y844782D03*
X287042Y393207D03*
Y845907D03*
X294542Y389332D03*
Y397082D03*
Y842032D03*
Y849782D03*
X411542Y392907D03*
X419042Y389032D03*
Y396782D03*
X411242Y845607D03*
X418742Y841732D03*
Y849482D03*
X535742Y393207D03*
X543242Y389332D03*
Y397082D03*
X575148Y846130D03*
X646742Y392907D03*
X654242Y389032D03*
Y396782D03*
X652142Y845607D03*
X659642Y841732D03*
Y849482D03*
X582648Y842255D03*
Y850005D03*
X1209611Y845907D03*
X1217111Y842032D03*
Y849782D03*
X1255445Y392994D03*
X1262945Y389119D03*
Y396869D03*
X1333824Y393151D03*
X1341324Y389276D03*
Y397026D03*
X1333824Y845907D03*
X1341324Y842032D03*
Y849782D03*
X1458036Y393151D03*
X1465536Y389276D03*
Y397026D03*
X1458036Y845907D03*
X1465536Y842032D03*
Y849782D03*
X1582249Y393151D03*
X1589749Y389276D03*
Y397026D03*
X1582249Y845907D03*
X1589749Y842032D03*
Y849782D03*
X1706461Y845907D03*
X1713961Y842032D03*
Y849782D03*
X1797642Y393507D03*
X1805142Y389632D03*
Y397382D03*
X1830674Y845907D03*
X1838174Y842032D03*
Y849782D03*
G54D24*
G01X466941Y-145664D02*
Y-225664D01*
G01D02*
X1593241D01*
G01X462941Y-129664D02*
G02I-12000J0D01*
G01X457791D02*
G02I-6850J0D01*
G01X450941Y-145664D02*
Y-113664D01*
G01X466941Y-129664D02*
X434941D01*
G01X466941Y-145664D02*
X1593241D01*
G01X466941Y-181164D02*
X1593241D01*
G01X805741Y-145664D02*
Y-225664D01*
G01X943241Y-145664D02*
Y-225664D01*
G01X1058241Y-145664D02*
Y-225664D01*
G01X1225741Y-145664D02*
Y-225664D01*
G01X1395741Y-145664D02*
Y-225664D01*
G01X1593241Y-145664D02*
Y-225664D01*
G01X1621241Y-129664D02*
G02I-12000J0D01*
G01X1616091D02*
G02I-6850J0D01*
G01X1609241Y-145664D02*
Y-113664D01*
G01X1625241Y-129664D02*
X1593241D01*
X100412Y6000D03*
X95412D03*
X90412D03*
X85412D03*
X80412D03*
X75412D03*
X70412D03*
X65412D03*
X60412D03*
X55412D03*
X50412D03*
X45412D03*
X40412D03*
X35412D03*
X30412D03*
X25412D03*
X20412D03*
X15412D03*
X10412D03*
X6000Y6588D03*
Y11588D03*
Y16588D03*
Y21588D03*
Y26588D03*
Y31588D03*
Y36588D03*
Y41588D03*
Y46588D03*
Y51588D03*
Y56588D03*
Y61588D03*
Y66588D03*
Y71588D03*
Y76588D03*
Y81588D03*
Y86588D03*
Y91588D03*
Y96588D03*
Y101588D03*
Y106588D03*
Y111588D03*
Y116588D03*
Y121588D03*
Y126588D03*
Y131588D03*
Y136588D03*
Y141588D03*
Y146588D03*
Y151588D03*
Y156588D03*
Y161588D03*
Y166588D03*
Y171588D03*
Y176588D03*
Y181588D03*
Y186588D03*
Y191588D03*
Y196588D03*
Y201588D03*
Y206588D03*
Y211588D03*
Y216588D03*
Y221588D03*
Y226588D03*
Y231588D03*
Y236588D03*
Y241588D03*
Y246588D03*
Y251588D03*
Y256588D03*
Y261588D03*
Y266588D03*
Y271588D03*
Y276588D03*
Y281588D03*
Y286588D03*
Y291588D03*
Y296588D03*
Y301588D03*
Y306588D03*
Y311588D03*
Y316588D03*
Y321588D03*
Y326588D03*
Y331588D03*
Y336588D03*
Y341588D03*
Y346588D03*
Y351588D03*
Y356588D03*
Y361588D03*
Y366588D03*
Y371588D03*
Y376588D03*
Y441588D03*
Y436588D03*
Y431588D03*
Y426588D03*
Y421588D03*
Y416588D03*
Y411588D03*
Y406588D03*
Y386588D03*
Y391588D03*
Y396588D03*
Y401588D03*
Y446588D03*
Y451588D03*
Y456588D03*
Y461588D03*
Y381588D03*
Y466588D03*
Y471588D03*
Y476588D03*
Y481588D03*
Y486588D03*
Y491588D03*
Y496588D03*
Y501588D03*
Y506588D03*
Y511588D03*
Y516588D03*
Y521588D03*
Y526588D03*
Y531588D03*
Y536588D03*
Y541588D03*
Y546588D03*
Y551588D03*
Y556588D03*
Y561588D03*
Y566588D03*
Y571588D03*
Y576588D03*
Y581588D03*
Y586588D03*
Y591588D03*
Y596588D03*
Y601588D03*
Y606588D03*
Y611588D03*
Y616588D03*
Y621588D03*
Y626588D03*
Y631588D03*
Y636588D03*
Y641588D03*
Y646588D03*
Y651588D03*
Y656588D03*
Y661588D03*
Y666588D03*
Y671588D03*
Y676588D03*
Y681588D03*
Y686588D03*
Y691588D03*
Y696588D03*
Y701588D03*
Y706588D03*
Y711588D03*
Y716588D03*
Y721588D03*
Y726588D03*
Y731588D03*
Y736588D03*
Y741588D03*
Y746588D03*
Y751588D03*
Y756588D03*
Y761588D03*
Y766588D03*
Y771588D03*
Y776588D03*
Y781588D03*
Y786588D03*
Y791588D03*
Y796588D03*
Y801588D03*
Y806588D03*
Y811588D03*
Y816588D03*
Y821588D03*
Y826588D03*
Y831588D03*
Y836588D03*
Y841588D03*
Y846588D03*
Y851588D03*
Y856588D03*
Y861588D03*
Y866588D03*
Y871588D03*
Y876588D03*
Y881588D03*
Y886588D03*
Y891588D03*
Y896588D03*
Y901588D03*
Y906588D03*
Y911588D03*
Y916588D03*
Y921588D03*
Y926588D03*
Y931588D03*
Y936588D03*
Y941588D03*
Y946588D03*
Y951588D03*
X26300Y873700D03*
Y864100D03*
Y868900D03*
X21500Y873700D03*
Y864100D03*
Y868900D03*
X6000Y956588D03*
Y961588D03*
Y966588D03*
Y971588D03*
Y976588D03*
Y981588D03*
Y986588D03*
Y991588D03*
Y996588D03*
Y1001588D03*
Y1006588D03*
Y1011588D03*
Y1016588D03*
Y1021588D03*
Y1026588D03*
Y1031588D03*
Y1036588D03*
Y1041588D03*
Y1046588D03*
Y1051588D03*
Y1056588D03*
Y1061588D03*
Y1066588D03*
Y1071588D03*
Y1076588D03*
Y1081588D03*
Y1086588D03*
Y1091588D03*
Y1096588D03*
Y1101588D03*
Y1106588D03*
Y1111588D03*
Y1116588D03*
Y1121588D03*
Y1126588D03*
Y1131588D03*
Y1136588D03*
Y1141588D03*
Y1146588D03*
Y1151588D03*
Y1156588D03*
Y1161588D03*
Y1166588D03*
Y1171588D03*
Y1176588D03*
Y1181588D03*
Y1186588D03*
Y1191588D03*
Y1196588D03*
Y1201588D03*
Y1206588D03*
Y1211588D03*
Y1216588D03*
Y1221588D03*
Y1226588D03*
Y1231588D03*
Y1236588D03*
Y1321588D03*
Y1326588D03*
Y1331588D03*
Y1286588D03*
Y1291588D03*
Y1296588D03*
Y1301588D03*
Y1306588D03*
Y1311588D03*
Y1316588D03*
Y1241588D03*
Y1246588D03*
Y1251588D03*
Y1256588D03*
Y1261588D03*
Y1266588D03*
Y1271588D03*
Y1276588D03*
Y1281588D03*
Y1421588D03*
Y1416588D03*
Y1411588D03*
Y1406588D03*
Y1401588D03*
Y1396588D03*
Y1391588D03*
Y1386588D03*
Y1381588D03*
Y1376588D03*
Y1371588D03*
Y1366588D03*
Y1361588D03*
Y1356588D03*
Y1351588D03*
Y1346588D03*
Y1341588D03*
Y1426588D03*
Y1336588D03*
Y1451588D03*
Y1446588D03*
Y1441588D03*
Y1436588D03*
Y1431588D03*
X99000Y1501000D03*
X61500Y1502000D03*
X87539Y1499118D03*
X82539D03*
X77539D03*
X72539D03*
X67539D03*
X92539D03*
X11000Y1455500D03*
X15500Y1458500D03*
X17811Y1462693D03*
Y1467693D03*
Y1472693D03*
Y1477693D03*
Y1482693D03*
Y1487693D03*
Y1492693D03*
Y1497693D03*
Y1502693D03*
Y1507693D03*
X17500Y1512000D03*
X21819Y1513685D03*
X26819D03*
X31819D03*
X36819D03*
X41819D03*
X46819D03*
X51819D03*
X56819D03*
X58500Y1508000D03*
X195412Y6000D03*
X190412D03*
X185412D03*
X180412D03*
X175412D03*
X170412D03*
X165412D03*
X160412D03*
X155412D03*
X150412D03*
X145412D03*
X140412D03*
X135412D03*
X130412D03*
X125412D03*
X120412D03*
X115412D03*
X110412D03*
X105412D03*
X127600Y437500D03*
Y432700D03*
X122800Y437500D03*
Y432700D03*
X127600Y427900D03*
X122800D03*
X169215Y876085D03*
Y880885D03*
X154215D03*
Y876085D03*
X169215Y895685D03*
Y890885D03*
X154215Y895685D03*
Y890885D03*
X164200Y885700D03*
X158900D03*
X192963Y888625D03*
Y883625D03*
X188163Y888625D03*
X183363D03*
X178563D03*
Y883625D03*
X173763D03*
Y888625D03*
X183363Y883625D03*
X188163D03*
X113363Y884925D03*
X180000Y1424000D03*
Y1430000D03*
X186000Y1424000D03*
Y1430000D03*
X152000Y1377000D03*
Y1383000D03*
X158000Y1377000D03*
Y1383000D03*
X170000D03*
Y1377000D03*
X164000Y1383000D03*
Y1377000D03*
X102000Y1505500D03*
X177433Y1513685D03*
X182433D03*
X187433D03*
X192433D03*
X147433D03*
X152433D03*
X157433D03*
X162433D03*
X167433D03*
X172433D03*
X103000Y1511000D03*
X107433Y1513685D03*
X112433D03*
X117433D03*
X122433D03*
X127433D03*
X132433D03*
X137433D03*
X142433D03*
X290412Y6000D03*
X285412D03*
X280412D03*
X275412D03*
X270412D03*
X265412D03*
X260412D03*
X255412D03*
X250412D03*
X245412D03*
X240412D03*
X235412D03*
X230412D03*
X225412D03*
X220412D03*
X215412D03*
X210412D03*
X205412D03*
X200412D03*
X251200Y457900D03*
Y438300D03*
Y443100D03*
Y453100D03*
X291500Y451100D03*
Y446100D03*
X286700D03*
Y451100D03*
X281900D03*
Y446100D03*
X272300D03*
Y451100D03*
X277100Y446100D03*
Y451100D03*
X267752Y458160D03*
Y438560D03*
Y443360D03*
Y453360D03*
X257127Y448364D03*
X261927D03*
X211590Y427289D03*
X211190Y447189D03*
X197763Y888625D03*
Y883625D03*
X233074Y1429500D03*
X239274Y1429600D03*
X237235Y1419039D03*
X236974Y1425000D03*
X283000Y1492000D03*
X279000Y1498500D03*
X197433Y1513685D03*
X202433D03*
X207433D03*
X212433D03*
X217433D03*
X222433D03*
X227433D03*
X232433D03*
X237433D03*
X242433D03*
X247433D03*
X252433D03*
X257433D03*
X262433D03*
X267433D03*
X272433D03*
X277433D03*
X278646Y1509398D03*
Y1504398D03*
X288685Y1490063D03*
X385412Y6000D03*
X380412D03*
X375412D03*
X370412D03*
X365412D03*
X360412D03*
X355412D03*
X350412D03*
X345412D03*
X340412D03*
X335412D03*
X330412D03*
X325412D03*
X320412D03*
X315412D03*
X310412D03*
X305412D03*
X300412D03*
X295412D03*
X296300Y446100D03*
Y451100D03*
X380780Y1428599D03*
Y1422599D03*
Y1416599D03*
Y1410599D03*
X374780Y1428599D03*
Y1422599D03*
Y1416599D03*
Y1410599D03*
X293685Y1490063D03*
X298685D03*
X303685D03*
X308685D03*
X313685D03*
X318685D03*
X323685D03*
X328685D03*
X333685D03*
X338685D03*
X343685D03*
X348685D03*
X353685D03*
X358685D03*
X363685D03*
X368685D03*
X373685D03*
X378685D03*
X383685D03*
X380780Y1434599D03*
X374780D03*
X480412Y6000D03*
X475412D03*
X470412D03*
X465412D03*
X460412D03*
X455412D03*
X450412D03*
X445412D03*
X440412D03*
X435412D03*
X430412D03*
X425412D03*
X420412D03*
X415412D03*
X410412D03*
X405412D03*
X400412D03*
X395412D03*
X390412D03*
X388685Y1490063D03*
X393685D03*
X398685D03*
X403685D03*
X408685D03*
X413685D03*
X418685D03*
X423685D03*
X428685D03*
X433685D03*
X438685D03*
X443685D03*
X448685D03*
X453685D03*
X458685D03*
X463685D03*
X468685D03*
X473685D03*
X478685D03*
X575412Y6000D03*
X570412D03*
X565412D03*
X560412D03*
X555412D03*
X550412D03*
X545412D03*
X540412D03*
X535412D03*
X530412D03*
X525412D03*
X520412D03*
X515412D03*
X510412D03*
X505412D03*
X500412D03*
X495412D03*
X490412D03*
X485412D03*
X501000Y1494000D03*
X503000Y1499000D03*
X494500Y1490500D03*
X574937Y1513685D03*
X569937D03*
X564937D03*
X559937D03*
X554937D03*
X549937D03*
X544937D03*
X539937D03*
X534937D03*
X529937D03*
X524937D03*
X483685Y1490063D03*
X488685D03*
X503244Y1504378D03*
Y1509378D03*
X504937Y1513685D03*
X509937D03*
X514937D03*
X519937D03*
X513917Y1447297D03*
X507917D03*
X519717D03*
X670412Y6000D03*
X665412D03*
X660412D03*
X655412D03*
X650412D03*
X645412D03*
X640412D03*
X635412D03*
X630412D03*
X625412D03*
X620412D03*
X615412D03*
X610412D03*
X605412D03*
X600412D03*
X595412D03*
X590412D03*
X585412D03*
X580412D03*
X669937Y1513685D03*
X659937D03*
X654937D03*
X649937D03*
X644937D03*
X639937D03*
X634937D03*
X629937D03*
X624937D03*
X619937D03*
X614937D03*
X609937D03*
X604937D03*
X599937D03*
X594937D03*
X589937D03*
X584937D03*
X579937D03*
X664937D03*
X765412Y6000D03*
X760412D03*
X755412D03*
X750412D03*
X745412D03*
X740412D03*
X735412D03*
X730412D03*
X725412D03*
X720412D03*
X715412D03*
X710412D03*
X705412D03*
X700412D03*
X695412D03*
X690412D03*
X685412D03*
X680412D03*
X675412D03*
X722000Y1503500D03*
X718500Y1500000D03*
X680500Y1503500D03*
X674937Y1513685D03*
X688012Y1499118D03*
X693012D03*
X698012D03*
X703012D03*
X708012D03*
X713012D03*
X724000Y1509500D03*
X725551Y1513685D03*
X730551D03*
X735551D03*
X740551D03*
X745551D03*
X750551D03*
X755551D03*
X760551D03*
X765551D03*
X678500Y1510500D03*
X777465Y93947D03*
Y88947D03*
Y83947D03*
Y78947D03*
Y73947D03*
Y68947D03*
Y63947D03*
Y58947D03*
Y53947D03*
Y48947D03*
Y43947D03*
Y38947D03*
Y33947D03*
Y28947D03*
Y23947D03*
Y18947D03*
Y13947D03*
X778000Y9500D03*
X775412Y6000D03*
X770412D03*
X777465Y183947D03*
Y178947D03*
Y173947D03*
Y168947D03*
Y163947D03*
Y158947D03*
Y153947D03*
Y148947D03*
Y143947D03*
Y138947D03*
Y133947D03*
Y128947D03*
Y123947D03*
Y118947D03*
Y113947D03*
Y108947D03*
Y103947D03*
Y98947D03*
X809500Y197500D03*
X805522Y195764D03*
X808961Y201678D03*
Y206678D03*
Y211678D03*
Y216678D03*
Y236678D03*
Y231678D03*
Y226678D03*
Y221678D03*
Y241678D03*
X779022Y190764D03*
X784022Y194764D03*
X800522Y195764D03*
X795522D03*
X790522D03*
X826843Y409096D03*
Y404296D03*
Y399496D03*
X822043D03*
Y404296D03*
Y409096D03*
X807643Y408996D03*
Y404196D03*
Y399396D03*
X802843D03*
Y404196D03*
Y408996D03*
X826843Y419764D03*
Y424564D03*
Y429364D03*
X802843Y419664D03*
X807643D03*
X822043Y419764D03*
X802843Y429264D03*
Y424464D03*
X807643D03*
Y429264D03*
X822043Y429364D03*
Y424564D03*
X822400Y567100D03*
Y562300D03*
Y557500D03*
X817600D03*
Y562300D03*
Y567100D03*
X803200Y557400D03*
Y562200D03*
Y567000D03*
X798400Y557400D03*
Y562200D03*
Y567000D03*
X822400Y587368D03*
Y582568D03*
X817600D03*
Y587368D03*
X803200Y587268D03*
Y582468D03*
X798400D03*
Y587268D03*
X822400Y577768D03*
X817600D03*
X803200Y577668D03*
X798400D03*
X808300Y1197300D03*
X813100D03*
Y1206900D03*
Y1202100D03*
X808300D03*
Y1206900D03*
X794100Y1197300D03*
X789300D03*
X794100Y1202100D03*
Y1206900D03*
X789300Y1202100D03*
Y1206900D03*
X808300Y1227168D03*
Y1222368D03*
X813100D03*
Y1227168D03*
X794100D03*
Y1222368D03*
X789300D03*
Y1227168D03*
X813100Y1217568D03*
X808300D03*
X789300D03*
X794100D03*
X779500Y1491000D03*
X775000Y1495500D03*
X770551Y1513685D03*
X773528Y1510662D03*
Y1505662D03*
Y1500662D03*
X786803Y1490063D03*
X791803D03*
X796803D03*
X801803D03*
X806803D03*
X811803D03*
X816803D03*
X821803D03*
X826803D03*
X831803D03*
X836803D03*
X841803D03*
X846803D03*
X851803D03*
X856803D03*
X861803D03*
X887127Y254031D03*
X944200Y1083100D03*
X938900Y1103700D03*
X938800Y1109300D03*
X945200Y1398300D03*
Y1393500D03*
X950200Y1394500D03*
X866803Y1490063D03*
X871803D03*
X876803D03*
X881803D03*
X886803D03*
X891803D03*
X896803D03*
X901803D03*
X906803D03*
X911803D03*
X916803D03*
X921803D03*
X926803D03*
X931803D03*
X936803D03*
X941803D03*
X946803D03*
X951803D03*
X956803D03*
X1012000Y371369D03*
X1015537Y365911D03*
X1038200Y762300D03*
X1021194Y766883D03*
X1035594Y766983D03*
X1040394D03*
X1021194Y771683D03*
Y776483D03*
X1035594Y776583D03*
Y771783D03*
X1040394D03*
Y776583D03*
X1016394Y766883D03*
Y776483D03*
Y771683D03*
X997000Y1496000D03*
X993000Y1491500D03*
X961803Y1490063D03*
X966803D03*
X971803D03*
X976803D03*
X981803D03*
X986803D03*
X998126Y1503614D03*
Y1508614D03*
Y1513614D03*
X1003126D03*
X1008126D03*
X1013126D03*
X1018126D03*
X1023126D03*
X1028126D03*
X1033126D03*
X1038126D03*
X1043126D03*
X1048126D03*
X1053126D03*
X1068734Y195764D03*
X1064500Y197500D03*
X1065055Y201895D03*
Y206895D03*
Y211895D03*
Y216895D03*
Y226895D03*
Y231895D03*
Y236895D03*
Y241895D03*
Y221895D03*
X1148734Y195764D03*
X1143734D03*
X1138734D03*
X1133734D03*
X1128734D03*
X1123734D03*
X1118734D03*
X1113734D03*
X1103734D03*
X1098734D03*
X1093734D03*
X1088734D03*
X1083734D03*
X1078734D03*
X1073734D03*
X1075627Y374973D03*
X1075829Y380885D03*
X1119877Y408072D03*
Y403272D03*
Y398472D03*
X1124677D03*
Y403272D03*
Y408072D03*
X1100677Y407972D03*
Y403172D03*
Y398372D03*
X1105477D03*
Y403172D03*
Y407972D03*
X1119877Y423540D03*
Y428340D03*
Y418740D03*
X1124677Y428340D03*
Y423540D03*
Y418740D03*
X1105477Y428240D03*
Y423440D03*
X1100677D03*
Y428240D03*
X1105477Y418640D03*
X1100677D03*
X1076142Y386839D03*
X1057400Y771600D03*
X1057600Y776500D03*
X1067200Y786500D03*
X1062400D03*
Y781500D03*
X1057600Y786500D03*
Y781500D03*
X1067200Y791500D03*
X1062400D03*
X1067200Y796500D03*
X1062400D03*
X1057600D03*
Y791500D03*
X1128700Y1206500D03*
X1133500D03*
Y1201700D03*
X1128700D03*
X1133500Y1196900D03*
X1128700D03*
X1109600Y1197100D03*
X1114400D03*
X1109600Y1201900D03*
X1114400D03*
Y1206700D03*
X1109600D03*
X1128500Y1225700D03*
X1133300D03*
X1109400Y1221100D03*
X1114200D03*
Y1225900D03*
X1109400D03*
X1133300Y1220900D03*
X1128500D03*
X1133300Y1216100D03*
X1128500D03*
X1109400Y1216300D03*
X1114200D03*
X1087933Y1411323D03*
X1082933D03*
X1077933D03*
X1095567Y1426057D03*
X1117200Y1346700D03*
X1058126Y1513614D03*
X1061675Y1510352D03*
X1065210Y1506817D03*
X1066638Y1472408D03*
Y1467408D03*
Y1462408D03*
Y1457408D03*
Y1452408D03*
Y1447408D03*
Y1442408D03*
X1095567Y1431057D03*
Y1436057D03*
Y1441057D03*
Y1446057D03*
Y1451057D03*
Y1456057D03*
Y1461057D03*
Y1466057D03*
X1096039Y1505861D03*
X1099575Y1509397D03*
X1103110Y1512932D03*
X1107798Y1513685D03*
X1112798D03*
X1117798D03*
X1122798D03*
X1127798D03*
X1132798D03*
X1137798D03*
X1142798D03*
X1147798D03*
X1095567Y1471057D03*
X1066638Y1502408D03*
X1115000Y1485000D03*
X1118000Y1480500D03*
X1112000D03*
X1234500Y6000D03*
X1243844D03*
X1238844D03*
X1230409Y7565D03*
Y12565D03*
Y17565D03*
Y22565D03*
Y27565D03*
Y32565D03*
Y37565D03*
Y42565D03*
Y47565D03*
Y52565D03*
Y57565D03*
Y62565D03*
Y67565D03*
Y72565D03*
Y77565D03*
Y82565D03*
Y87565D03*
Y92565D03*
X1229000Y189500D03*
X1230409Y97565D03*
Y102565D03*
Y107565D03*
Y112565D03*
Y117565D03*
Y122565D03*
Y127565D03*
Y132565D03*
Y137565D03*
Y142565D03*
Y147565D03*
Y152565D03*
Y157565D03*
Y162565D03*
Y167565D03*
Y172565D03*
Y177565D03*
Y182565D03*
X1225000Y194000D03*
X1218734Y195764D03*
X1213734D03*
X1208734D03*
X1203734D03*
X1198734D03*
X1193734D03*
X1188734D03*
X1183734D03*
X1178734D03*
X1173734D03*
X1168734D03*
X1163734D03*
X1158734D03*
X1153734D03*
X1151100Y1179300D03*
X1155900D03*
X1151100Y1184100D03*
X1155900D03*
Y1188900D03*
X1151100D03*
X1245500Y1500500D03*
X1208000Y1502500D03*
X1234783Y1499118D03*
X1229783D03*
X1224783D03*
X1219783D03*
X1214783D03*
X1239783D03*
X1152798Y1513685D03*
X1157798D03*
X1162798D03*
X1167798D03*
X1172798D03*
X1177798D03*
X1182798D03*
X1187798D03*
X1192798D03*
X1197798D03*
X1202798D03*
X1205500Y1509000D03*
X1338844Y6000D03*
X1333844D03*
X1328844D03*
X1323844D03*
X1318844D03*
X1313844D03*
X1308844D03*
X1303844D03*
X1298844D03*
X1293844D03*
X1288844D03*
X1283844D03*
X1278844D03*
X1273844D03*
X1268844D03*
X1263844D03*
X1258844D03*
X1253844D03*
X1248844D03*
X1249000Y1504500D03*
X1328464Y1513685D03*
X1333464D03*
X1338464D03*
X1293464D03*
X1298464D03*
X1303464D03*
X1308464D03*
X1313464D03*
X1318464D03*
X1323464D03*
X1250500Y1510500D03*
X1253464Y1513685D03*
X1258464D03*
X1263464D03*
X1268464D03*
X1273464D03*
X1278464D03*
X1283464D03*
X1288464D03*
X1433844Y6000D03*
X1428844D03*
X1423844D03*
X1418844D03*
X1413844D03*
X1408844D03*
X1403844D03*
X1398844D03*
X1393844D03*
X1388844D03*
X1383844D03*
X1378844D03*
X1373844D03*
X1368844D03*
X1363844D03*
X1358844D03*
X1353844D03*
X1348844D03*
X1343844D03*
X1385474Y1429500D03*
X1380074D03*
X1383374Y1425000D03*
X1383674Y1419000D03*
X1433500Y1490500D03*
X1428500Y1494000D03*
X1403500Y1513500D03*
X1398500D03*
X1363464Y1513685D03*
X1368464D03*
X1373464D03*
X1378464D03*
X1383464D03*
X1388464D03*
X1393464D03*
X1353464D03*
X1358464D03*
X1343464D03*
X1348464D03*
X1408464D03*
X1413464D03*
X1418464D03*
X1423464D03*
X1425890Y1510111D03*
Y1505111D03*
Y1500111D03*
X1528844Y6000D03*
X1523844D03*
X1518844D03*
X1513844D03*
X1508844D03*
X1503844D03*
X1498844D03*
X1493844D03*
X1488844D03*
X1483844D03*
X1478844D03*
X1473844D03*
X1468844D03*
X1463844D03*
X1458844D03*
X1453844D03*
X1448844D03*
X1443844D03*
X1438844D03*
X1439716Y1490063D03*
X1444716D03*
X1449716D03*
X1454716D03*
X1459716D03*
X1464716D03*
X1469716D03*
X1474716D03*
X1479716D03*
X1484716D03*
X1489716D03*
X1494716D03*
X1499716D03*
X1504716D03*
X1509716D03*
X1514716D03*
X1519716D03*
X1524716D03*
X1529716D03*
X1623844Y6000D03*
X1618844D03*
X1613844D03*
X1608844D03*
X1603844D03*
X1598844D03*
X1593844D03*
X1588844D03*
X1583844D03*
X1578844D03*
X1573844D03*
X1568844D03*
X1563844D03*
X1558844D03*
X1553844D03*
X1548844D03*
X1543844D03*
X1538844D03*
X1533844D03*
X1534716Y1490063D03*
X1539716D03*
X1544716D03*
X1549716D03*
X1554716D03*
X1559716D03*
X1564716D03*
X1569716D03*
X1574716D03*
X1579716D03*
X1584716D03*
X1589716D03*
X1594716D03*
X1599716D03*
X1604716D03*
X1609716D03*
X1614716D03*
X1619716D03*
X1624716D03*
X1718844Y6000D03*
X1713844D03*
X1708844D03*
X1703844D03*
X1698844D03*
X1693844D03*
X1688844D03*
X1683844D03*
X1678844D03*
X1673844D03*
X1668844D03*
X1663844D03*
X1658844D03*
X1653844D03*
X1648844D03*
X1643844D03*
X1638844D03*
X1633844D03*
X1628844D03*
X1667359Y434407D03*
Y439207D03*
Y429607D03*
X1662559D03*
Y434407D03*
Y439207D03*
X1649500Y1497500D03*
X1646000Y1492000D03*
X1720968Y1513685D03*
X1715968D03*
X1710968D03*
X1705968D03*
X1700968D03*
X1695968D03*
X1690968D03*
X1685968D03*
X1680968D03*
X1670968D03*
X1675968D03*
X1629716Y1490063D03*
X1634716D03*
X1639716D03*
X1650488Y1504165D03*
Y1509165D03*
X1650968Y1513685D03*
X1655968D03*
X1660968D03*
X1665968D03*
X1813844Y6000D03*
X1808844D03*
X1803844D03*
X1798844D03*
X1793844D03*
X1788844D03*
X1783844D03*
X1778844D03*
X1773844D03*
X1768844D03*
X1763844D03*
X1758844D03*
X1753844D03*
X1748844D03*
X1743844D03*
X1738844D03*
X1733844D03*
X1728844D03*
X1723844D03*
X1814463Y449725D03*
Y454725D03*
X1804900Y451800D03*
X1809915Y461785D03*
Y446985D03*
Y456985D03*
Y442185D03*
X1799600Y451800D03*
X1794915Y461785D03*
Y446985D03*
Y456985D03*
Y442185D03*
X1751774Y430510D03*
X1753959Y450607D03*
X1741159Y873707D03*
X1736359D03*
X1741159Y864107D03*
X1736359D03*
X1741159Y868907D03*
X1736359D03*
X1766526Y1429400D03*
X1760326Y1429500D03*
X1763926Y1419000D03*
X1763626Y1425000D03*
X1786004Y1513500D03*
X1780968Y1513685D03*
X1775968D03*
X1770968D03*
X1765968D03*
X1760968D03*
X1755968D03*
X1750968D03*
X1745968D03*
X1740968D03*
X1796004Y1513500D03*
X1801004D03*
X1806004D03*
X1811004D03*
X1816004D03*
X1730968Y1513685D03*
X1725968D03*
X1791004Y1513500D03*
X1735968Y1513685D03*
X1913844Y6000D03*
X1908844D03*
X1903844D03*
X1898844D03*
X1893844D03*
X1888844D03*
X1883844D03*
X1878844D03*
X1873844D03*
X1868844D03*
X1863844D03*
X1858844D03*
X1853844D03*
X1848844D03*
X1843844D03*
X1838844D03*
X1833844D03*
X1828844D03*
X1823844D03*
X1818844D03*
X1838463Y454725D03*
Y449725D03*
X1819263D03*
Y454725D03*
X1833663D03*
Y449725D03*
X1828863D03*
Y454725D03*
X1824063D03*
Y449725D03*
X1912663Y888925D03*
Y883925D03*
X1869115Y876385D03*
Y891185D03*
Y881185D03*
Y895985D03*
X1873800Y886300D03*
X1884115Y876385D03*
X1898263Y883925D03*
Y888925D03*
X1903063D03*
Y883925D03*
X1907863D03*
Y888925D03*
X1884115Y891185D03*
Y881185D03*
Y895985D03*
X1893463Y888925D03*
Y883925D03*
X1879100Y886300D03*
X1888663Y888925D03*
Y883925D03*
X1828363Y884925D03*
X1869500Y1503500D03*
X1865500Y1500000D03*
X1829500Y1501500D03*
X1826500Y1506500D03*
X1855256Y1499118D03*
X1850256D03*
X1845256D03*
X1840256D03*
X1826040Y1513315D03*
X1821040D03*
X1835256Y1499118D03*
X1860256D03*
X1871157Y1509110D03*
X1871582Y1513685D03*
X1876582D03*
X1881582D03*
X1886582D03*
X1891582D03*
X1896582D03*
X1901582D03*
X1906582D03*
X1911582D03*
X1928843Y8985D03*
Y93985D03*
Y88985D03*
Y83985D03*
Y78985D03*
Y73985D03*
Y68985D03*
Y63985D03*
Y58985D03*
Y53985D03*
Y48985D03*
Y43985D03*
Y38985D03*
Y28985D03*
Y23985D03*
Y18985D03*
Y13985D03*
Y33985D03*
X1923844Y6000D03*
X1918844D03*
X1928843Y98985D03*
Y188985D03*
Y183985D03*
Y178985D03*
Y173985D03*
Y168985D03*
Y163985D03*
Y158985D03*
Y153985D03*
Y148985D03*
Y143985D03*
Y138985D03*
Y133985D03*
Y128985D03*
Y123985D03*
Y118985D03*
Y113985D03*
Y108985D03*
Y103985D03*
Y283985D03*
Y278985D03*
Y273985D03*
Y268985D03*
Y263985D03*
Y258985D03*
Y253985D03*
Y248985D03*
Y243985D03*
Y238985D03*
Y233985D03*
Y228985D03*
Y223985D03*
Y218985D03*
Y213985D03*
Y208985D03*
Y203985D03*
Y198985D03*
Y193985D03*
Y378985D03*
Y373985D03*
Y368985D03*
Y363985D03*
Y358985D03*
Y353985D03*
Y348985D03*
Y343985D03*
Y338985D03*
Y333985D03*
Y328985D03*
Y323985D03*
Y318985D03*
Y313985D03*
Y308985D03*
Y303985D03*
Y298985D03*
Y293985D03*
Y288985D03*
Y418985D03*
Y433985D03*
Y428985D03*
Y423985D03*
Y473985D03*
Y468985D03*
Y463985D03*
Y458985D03*
Y453985D03*
Y448985D03*
Y443985D03*
Y438985D03*
Y413985D03*
Y408985D03*
Y403985D03*
Y398985D03*
Y393985D03*
Y388985D03*
Y383985D03*
Y568985D03*
Y563985D03*
Y558985D03*
Y553985D03*
Y548985D03*
Y543985D03*
Y538985D03*
Y533985D03*
Y528985D03*
Y523985D03*
Y518985D03*
Y513985D03*
Y508985D03*
Y503985D03*
Y498985D03*
Y493985D03*
Y488985D03*
Y483985D03*
Y478985D03*
Y663985D03*
Y658985D03*
Y653985D03*
Y648985D03*
Y643985D03*
Y638985D03*
Y633985D03*
Y628985D03*
Y623985D03*
Y618985D03*
Y613985D03*
Y608985D03*
Y603985D03*
Y598985D03*
Y593985D03*
Y588985D03*
Y583985D03*
Y578985D03*
Y573985D03*
Y758985D03*
Y753985D03*
Y748985D03*
Y743985D03*
Y738985D03*
Y733985D03*
Y728985D03*
Y723985D03*
Y718985D03*
Y713985D03*
Y708985D03*
Y703985D03*
Y698985D03*
Y693985D03*
Y688985D03*
Y683985D03*
Y678985D03*
Y673985D03*
Y668985D03*
Y853985D03*
Y848985D03*
Y843985D03*
Y838985D03*
Y833985D03*
Y828985D03*
Y823985D03*
Y818985D03*
Y813985D03*
Y808985D03*
Y803985D03*
Y798985D03*
Y793985D03*
Y788985D03*
Y783985D03*
Y778985D03*
Y773985D03*
Y768985D03*
Y763985D03*
Y918985D03*
Y913985D03*
Y908985D03*
Y903985D03*
Y898985D03*
Y893985D03*
Y888985D03*
Y883985D03*
Y878985D03*
Y873985D03*
Y868985D03*
Y863985D03*
Y858985D03*
Y948985D03*
Y943985D03*
Y938985D03*
Y933985D03*
Y928985D03*
Y923985D03*
Y1043985D03*
Y1038985D03*
Y1033985D03*
Y1028985D03*
Y1023985D03*
Y1018985D03*
Y1013985D03*
Y1008985D03*
Y1003985D03*
Y998985D03*
Y993985D03*
Y988985D03*
Y983985D03*
Y978985D03*
Y973985D03*
Y968985D03*
Y963985D03*
Y958985D03*
Y953985D03*
Y1143985D03*
Y1138985D03*
Y1133985D03*
Y1128985D03*
Y1123985D03*
Y1118985D03*
Y1113985D03*
Y1108985D03*
Y1103985D03*
Y1098985D03*
Y1093985D03*
Y1088985D03*
Y1083985D03*
Y1078985D03*
Y1073985D03*
Y1068985D03*
Y1063985D03*
Y1058985D03*
Y1053985D03*
Y1048985D03*
Y1238985D03*
Y1233985D03*
Y1228985D03*
Y1223985D03*
Y1218985D03*
Y1213985D03*
Y1208985D03*
Y1203985D03*
Y1198985D03*
Y1193985D03*
Y1188985D03*
Y1183985D03*
Y1178985D03*
Y1173985D03*
Y1168985D03*
Y1163985D03*
Y1158985D03*
Y1153985D03*
Y1148985D03*
Y1288985D03*
Y1293985D03*
Y1298985D03*
Y1303985D03*
Y1308985D03*
Y1313985D03*
Y1318985D03*
Y1323985D03*
Y1328985D03*
Y1333985D03*
Y1283985D03*
Y1278985D03*
Y1273985D03*
Y1268985D03*
Y1263985D03*
Y1258985D03*
Y1253985D03*
Y1248985D03*
Y1243985D03*
Y1348985D03*
Y1353985D03*
Y1358985D03*
Y1363985D03*
Y1368985D03*
Y1373985D03*
Y1378985D03*
Y1383985D03*
Y1388985D03*
Y1393985D03*
Y1398985D03*
Y1403985D03*
Y1408985D03*
Y1413985D03*
Y1418985D03*
Y1423985D03*
Y1428985D03*
Y1338985D03*
Y1343985D03*
Y1448985D03*
Y1443985D03*
Y1433985D03*
Y1438985D03*
X1920000Y1458000D03*
X1917500Y1463500D03*
X1916582Y1513685D03*
X1917031Y1509134D03*
Y1504134D03*
Y1499134D03*
Y1494134D03*
Y1489134D03*
Y1484134D03*
Y1479134D03*
Y1474134D03*
Y1469134D03*
X1926500Y1455000D03*
G54D33*
X95500Y176200D03*
Y628700D03*
Y1081700D03*
X140500Y126300D03*
X219500Y176200D03*
X265000Y126400D03*
X219500Y628700D03*
X220000Y1081700D03*
X344000Y176200D03*
Y628700D03*
Y1081700D03*
X468000Y176200D03*
X389000Y126600D03*
X468000Y628700D03*
Y1081700D03*
X513600Y126500D03*
X528334Y1427929D03*
X528200Y1456800D03*
X592500Y176200D03*
X637300Y126500D03*
X592500Y628700D03*
Y1081700D03*
X651295Y1425119D03*
X716500Y176200D03*
X748400Y137300D03*
X716500Y628700D03*
X752500Y588200D03*
Y1048700D03*
X716500Y1081700D03*
X838470Y936630D03*
X958738Y1413018D03*
X1131215Y1310270D03*
X1213033Y1308144D03*
X1180009Y1308353D03*
X1298500Y146200D03*
Y175700D03*
X1253000Y126600D03*
X1298500Y599200D03*
Y628700D03*
X1252800Y579300D03*
Y1031900D03*
X1298500Y1051700D03*
Y1081200D03*
X1422500Y146200D03*
Y175700D03*
X1376700Y126600D03*
X1422500Y599200D03*
Y628700D03*
Y1051700D03*
Y1081200D03*
X1501300Y126600D03*
X1547000Y146200D03*
Y175700D03*
X1625300Y126600D03*
X1547000Y599200D03*
Y628700D03*
Y1051700D03*
Y1081200D03*
X1671000Y146200D03*
Y175700D03*
Y599200D03*
Y628700D03*
Y1051700D03*
Y1081200D03*
X1795000Y146200D03*
Y175700D03*
X1749700Y126100D03*
X1795000Y599200D03*
Y628700D03*
Y1051700D03*
Y1081200D03*
X1887000Y175700D03*
Y628700D03*
Y1081700D03*
G54D52*
X173228Y55118D03*
X421653Y94488D03*
X670078Y55118D03*
X1343701D03*
X1592126Y94488D03*
X1840551Y55118D03*
G54D34*
X73500Y126000D03*
X84500D03*
X69000Y140500D03*
X80000D03*
X73500Y578500D03*
X84500D03*
X69000Y593000D03*
X80000D03*
X73500Y1031500D03*
X84500D03*
X69000Y1046000D03*
X80000D03*
X193000Y140500D03*
Y593000D03*
X193500Y1046000D03*
X197500Y126000D03*
X208500D03*
X204000Y140500D03*
X197500Y578500D03*
X208500D03*
X204000Y593000D03*
X198000Y1031500D03*
X209000D03*
X204500Y1046000D03*
X322000Y126000D03*
X333000D03*
X317500Y140500D03*
X328500D03*
X322000Y578500D03*
X333000D03*
X317500Y593000D03*
X328500D03*
X322000Y1031500D03*
X333000D03*
X317500Y1046000D03*
X328500D03*
X446000Y126000D03*
X457000D03*
X441500Y140500D03*
X452500D03*
X446000Y578500D03*
X457000D03*
X441500Y593000D03*
X452500D03*
X446000Y1031500D03*
X457000D03*
X441500Y1046000D03*
X452500D03*
X570500Y126000D03*
X566000Y140500D03*
X577000D03*
X570500Y578500D03*
X566000Y593000D03*
X577000D03*
X570500Y1031500D03*
X566000Y1046000D03*
X577000D03*
X581500Y126000D03*
Y578500D03*
Y1031500D03*
X694500Y126000D03*
X705500D03*
X690000Y140500D03*
X701000D03*
X694500Y578500D03*
X705500D03*
X690000Y593000D03*
X701000D03*
X694500Y1031500D03*
X705500D03*
X690000Y1046000D03*
X701000D03*
X1310500Y126000D03*
X1299500D03*
X1319000Y159800D03*
X1308000D03*
X1310500Y579000D03*
X1299500D03*
X1318700Y612600D03*
X1307700D03*
X1310500Y1031500D03*
X1299500D03*
X1319000Y1065300D03*
X1308000D03*
X1434500Y126000D03*
X1423500D03*
X1431600Y159800D03*
X1434500Y579000D03*
X1423500D03*
X1432000Y612600D03*
X1434500Y1031500D03*
X1423500D03*
X1432000Y1065300D03*
X1442600Y159800D03*
X1443000Y612600D03*
Y1065300D03*
X1559000Y126000D03*
X1548000D03*
X1567400Y159800D03*
X1556400D03*
X1559000Y579000D03*
X1548000D03*
X1567300Y612600D03*
X1556300D03*
X1559000Y1031500D03*
X1548000D03*
X1567600Y1065500D03*
X1556600D03*
X1683000Y126000D03*
X1672000D03*
X1690400Y160000D03*
X1679400D03*
X1683000Y579000D03*
X1672000D03*
X1691600Y612500D03*
X1680600D03*
X1683000Y1031500D03*
X1672000D03*
X1691400Y1065300D03*
X1680400D03*
X1807000Y126000D03*
X1796000D03*
X1815500Y159700D03*
X1804500D03*
X1807000Y579000D03*
X1796000D03*
X1815800Y612500D03*
X1804800D03*
X1807000Y1031500D03*
X1796000D03*
X1815700Y1065300D03*
X1804700D03*
X1865000Y125500D03*
X1876000D03*
X1860500Y140000D03*
X1871500D03*
X1865000Y578500D03*
X1876000D03*
X1860500Y593000D03*
X1871500D03*
X1865000Y1031500D03*
X1876000D03*
X1860500Y1046000D03*
X1871500D03*
G54D109*
X1813566Y1484735D03*
X1816126D03*
Y1476665D03*
X1813566D03*
X1818686Y1484735D03*
Y1476665D03*
G54D61*
X184252Y1445275D03*
Y1466929D03*
X167716Y1445275D03*
Y1466929D03*
X233858Y1445275D03*
Y1466929D03*
X217322Y1445275D03*
Y1466929D03*
X200787Y1445275D03*
Y1466929D03*
X581102Y1445275D03*
Y1466929D03*
X564567Y1445275D03*
Y1466929D03*
X548031Y1445275D03*
Y1466929D03*
X614173Y1445275D03*
Y1466929D03*
X597637Y1445275D03*
Y1466929D03*
X1331496Y1445275D03*
Y1466929D03*
X1314960Y1445275D03*
Y1466929D03*
X1381102Y1445275D03*
Y1466929D03*
X1364566Y1445275D03*
Y1466929D03*
X1348031Y1445275D03*
Y1466929D03*
X1711811Y1445275D03*
Y1466929D03*
X1695275Y1445275D03*
Y1466929D03*
X1761417Y1445275D03*
Y1466929D03*
X1744881Y1445275D03*
Y1466929D03*
X1728346Y1445275D03*
Y1466929D03*
G54D16*
X60000Y73200D03*
Y525700D03*
X81700Y905280D03*
X77563Y905225D03*
X60000Y978700D03*
X131600Y126100D03*
X179527Y467544D03*
X175390Y467489D03*
X184000Y525700D03*
X184500Y978700D03*
X138974Y1429100D03*
X149374Y1457200D03*
Y1438700D03*
X207000Y77200D03*
X217000Y45200D03*
X254900Y126300D03*
X308500Y73200D03*
X379500Y126300D03*
X308500Y525700D03*
Y978700D03*
X454000Y80600D03*
X465500Y45200D03*
X432500Y525700D03*
Y978700D03*
X557000Y73200D03*
X503900Y126200D03*
X557000Y525700D03*
Y978700D03*
X502999Y1451632D03*
X628000Y126200D03*
X583550Y516250D03*
X655795Y1429619D03*
X628500Y1464700D03*
X704000Y77200D03*
X714000Y45200D03*
X707800Y516900D03*
X681000Y525700D03*
X752200Y579000D03*
X681000Y978700D03*
X676500Y1479700D03*
X841939Y389815D03*
X846939D03*
X822470Y927630D03*
Y977630D03*
X830470D03*
X839970Y969870D03*
X955000Y547800D03*
X952100Y520000D03*
X922100Y760700D03*
X948500Y849200D03*
X953000D03*
X911080Y864070D03*
X918380Y919114D03*
X914260Y919070D03*
X951500Y1229700D03*
X868900Y1188200D03*
X888000Y1197300D03*
X986200Y547700D03*
X983300Y522000D03*
X966093Y849200D03*
X993942Y879500D03*
X976242Y881200D03*
X980442Y879500D03*
X1000500Y910700D03*
X1005500D03*
X959500Y1229700D03*
X963238Y1417518D03*
X998325Y1467634D03*
X1013618Y1467565D03*
X1043606Y1448349D03*
X975438Y1453608D03*
X1122112Y1369973D03*
X1134112D03*
X1114112D03*
X1118112D03*
X1138112D03*
X1203394Y1343483D03*
X1222100D03*
X1236600D03*
X1232100D03*
X1217100D03*
X1183894D03*
X1188894D03*
X1198894D03*
X1203487Y1424641D03*
X1308000Y41700D03*
X1318000D03*
X1317800Y54000D03*
X1311700Y69100D03*
X1313700Y54000D03*
X1262600Y126300D03*
X1312000Y508200D03*
X1322000D03*
X1326500Y520700D03*
X1322000D03*
X1262600Y579000D03*
X1262400Y1031700D03*
X1312000Y960700D03*
X1322000D03*
X1326500Y973200D03*
X1322000D03*
X1296374Y1457200D03*
Y1438700D03*
X1436000Y55200D03*
X1387200Y126300D03*
X1436000Y508200D03*
X1386400Y579000D03*
X1387000Y1031800D03*
X1436000Y960700D03*
X1446000Y55200D03*
X1450500Y67700D03*
X1446000D03*
X1511400Y126300D03*
X1446000Y508200D03*
X1450500Y520700D03*
X1446000D03*
X1511200Y579000D03*
X1446000Y960700D03*
X1450500Y973200D03*
X1446000D03*
X1511400Y1031800D03*
X1557500Y41700D03*
X1567500D03*
X1572000Y54200D03*
X1563500Y69200D03*
X1567500Y54200D03*
X1560500Y508200D03*
X1570500D03*
X1575000Y520700D03*
X1570500D03*
X1560500Y960700D03*
X1570500D03*
X1575000Y973200D03*
X1570500D03*
X1684500Y55200D03*
X1694500D03*
X1699000Y67700D03*
X1694500D03*
X1635300Y126300D03*
X1722296Y470962D03*
X1718159Y470907D03*
X1684500Y508200D03*
X1694500D03*
X1699000Y520700D03*
X1694500D03*
X1634200Y579000D03*
X1635100Y1031800D03*
X1684500Y960700D03*
X1694500D03*
X1699000Y973200D03*
X1694500D03*
X1676626Y1457200D03*
Y1438700D03*
X1759600Y126300D03*
X1808500Y508200D03*
X1792563Y905225D03*
X1796700Y905280D03*
X1759300Y1031800D03*
X1808500Y960700D03*
X1884600Y45700D03*
X1862300Y30000D03*
X1818500Y508200D03*
X1823000Y520700D03*
X1818500D03*
X1853000Y510700D03*
X1848500D03*
X1843000Y541200D03*
X1818500Y960700D03*
X1823000Y973200D03*
X1818500D03*
X1875800Y988200D03*
X1853000Y963700D03*
X1848500D03*
X1843000Y994200D03*
G54D25*
X77300Y67250D03*
X60000Y80000D03*
X67750Y84500D03*
X77100Y62800D03*
X85600Y67700D03*
X83000Y147500D03*
X69000Y148000D03*
X86700Y133000D03*
X58709Y376696D03*
X72049Y349667D03*
X72600Y365900D03*
X53713Y367631D03*
X69567Y380781D03*
X77300Y519750D03*
X60000Y532500D03*
X68100Y537000D03*
X77200Y515100D03*
X86850Y520600D03*
X83000Y600000D03*
X69000Y600500D03*
X86500Y585400D03*
X57300Y751562D03*
X46442Y829350D03*
X72049Y808105D03*
X68109Y785607D03*
X44000Y819500D03*
X79563Y910125D03*
X97263Y913025D03*
X86263D03*
X77263Y894425D03*
X71313Y904525D03*
X70603Y887495D03*
X65763Y875525D03*
X86500Y1038500D03*
X77300Y972750D03*
X60000Y985500D03*
X69000Y989000D03*
X63000Y964500D03*
X83000Y970000D03*
Y1053000D03*
X69000Y1053500D03*
X188841Y79022D03*
X195250Y73500D03*
X151160Y18699D03*
X168100Y25300D03*
X168200Y20500D03*
X140200Y48400D03*
X144400Y40500D03*
X136200Y126150D03*
X193000Y148000D03*
X192842Y376350D03*
X180300Y330300D03*
X184060Y300300D03*
X187450Y445273D03*
X177390Y472389D03*
X195090Y475289D03*
X184090D03*
X175090Y456689D03*
X169140Y466789D03*
X168430Y449759D03*
X164418Y438162D03*
X184000Y532500D03*
X192499Y536649D03*
X137250Y588500D03*
X193000Y600500D03*
X169442Y829050D03*
X192321Y785355D03*
X165500Y822058D03*
X180300Y769500D03*
X129298Y888025D03*
X114563Y904041D03*
X112763Y869025D03*
X106363Y893425D03*
X102763Y873035D03*
X102207Y890524D03*
X102863Y880125D03*
X184500Y985500D03*
X193949Y989097D03*
X137250Y1041500D03*
X193500Y1053500D03*
X168674Y1414200D03*
X137634Y1416776D03*
X184874Y1412600D03*
X116374Y1497100D03*
X109774Y1480300D03*
X124174Y1466600D03*
X104974Y1485200D03*
X124574Y1488200D03*
X119074Y1442100D03*
X113314Y1445840D03*
X105974Y1469500D03*
X124134Y1474900D03*
X211000Y57400D03*
X211162Y45100D03*
X211086Y73750D03*
X207000Y147500D03*
X260400Y126350D03*
X210960Y132800D03*
X218200Y360600D03*
X204300Y351300D03*
X227434Y450289D03*
X212390Y466305D03*
X210596Y431445D03*
X204190Y455689D03*
X199590Y434639D03*
X200022Y452941D03*
X201190Y442389D03*
X201300Y519750D03*
X201000Y515300D03*
X211150Y520500D03*
X207000Y600000D03*
X261250Y588500D03*
X211000Y585600D03*
X196261Y807853D03*
X261500Y1042000D03*
X211000Y1038200D03*
X201800Y972750D03*
X201600Y968400D03*
X210850Y973800D03*
X208000Y1053000D03*
X244829Y1241403D03*
X218384Y1411500D03*
X325800Y67250D03*
X308500Y80000D03*
X316800Y84000D03*
X325900Y62900D03*
X335100Y67800D03*
X331500Y147500D03*
X384549Y126350D03*
X317500Y148000D03*
X335299Y133000D03*
X320474Y364117D03*
X316534Y341619D03*
X294542Y376650D03*
X294000Y366300D03*
X305400Y317825D03*
X325800Y519750D03*
X308500Y532500D03*
X320958Y533200D03*
X325800Y514700D03*
X335050Y520700D03*
X331500Y600000D03*
X385750Y588500D03*
X317500Y600500D03*
X335290Y585300D03*
X294542Y829350D03*
X320474Y812669D03*
X316534Y790171D03*
X294000Y819000D03*
X305400Y764768D03*
X312418Y868254D03*
X385750Y1041500D03*
X335100Y1038500D03*
X325800Y972750D03*
X308500Y985500D03*
X317542Y988731D03*
X325600Y968400D03*
X334750Y973200D03*
X331500Y1053000D03*
X317500Y1053500D03*
X372774Y1438648D03*
X459000Y57500D03*
X448200Y40150D03*
X445500Y74300D03*
X459511Y44500D03*
X458900Y76700D03*
X455500Y147500D03*
X441500Y148000D03*
X459400Y133100D03*
X429900Y278468D03*
X444687Y358540D03*
X440747Y336042D03*
X419042Y376350D03*
X418500Y366000D03*
X435190Y408695D03*
X449800Y519750D03*
X432500Y532500D03*
X440855Y536014D03*
X449800Y515400D03*
X459350Y520600D03*
X455500Y600000D03*
X441500Y600500D03*
X459500Y585400D03*
X429600Y761281D03*
X418742Y828794D03*
X444687Y807662D03*
X440747Y785164D03*
X415000Y819000D03*
X448289Y917775D03*
X434890Y861395D03*
X459100Y1038400D03*
X449800Y972750D03*
X432500Y985500D03*
X441398Y989368D03*
X449700Y968500D03*
X459150Y973500D03*
X455500Y1053000D03*
X441500Y1053500D03*
X478444Y1240034D03*
X428500Y1423500D03*
Y1430500D03*
X574300Y67250D03*
X557000Y80000D03*
X565757Y83609D03*
X574300Y62900D03*
X508761Y126250D03*
X566000Y148000D03*
X548228Y100997D03*
X536715Y271785D03*
X568899Y355752D03*
X564959Y333254D03*
X493899Y320895D03*
X488448Y338766D03*
X482745Y351821D03*
X543242Y376650D03*
X498968Y296814D03*
X505052Y368552D03*
X511136Y352328D03*
X517473Y332556D03*
X523810Y312530D03*
X531987Y294450D03*
X554100Y294300D03*
X557975Y412093D03*
X574300Y519750D03*
X557000Y532500D03*
X565500Y537000D03*
X574300Y515500D03*
X509750Y588500D03*
X566000Y600500D03*
X569000Y814761D03*
X564959Y791755D03*
X575148Y827910D03*
X509750Y1041500D03*
X574300Y972750D03*
X557000Y985500D03*
X566574Y988327D03*
X574200Y968300D03*
X566000Y1053500D03*
X547198Y1420600D03*
X497000Y1408500D03*
X539500Y1408000D03*
X553500D03*
X572000D03*
X583700Y68200D03*
X580000Y147500D03*
X632974Y126250D03*
X583724Y132900D03*
X665100Y275593D03*
X654242Y376350D03*
X653700Y366000D03*
X670390Y408695D03*
X583550Y520300D03*
Y508800D03*
X672050Y552553D03*
X580000Y600000D03*
X634250Y588500D03*
X583600Y585200D03*
X646680Y647138D03*
X582648Y829573D03*
X659642Y829050D03*
X652142Y822416D03*
X593680Y827400D03*
X670500Y829616D03*
X594056Y909112D03*
X598970Y862595D03*
X610207Y900960D03*
X634250Y1041500D03*
X583600Y1038500D03*
X583050Y973400D03*
X671359Y1006366D03*
X580000Y1053000D03*
X607000Y1291500D03*
X663263Y1427653D03*
X590500Y1408500D03*
X646226Y1433033D03*
X663109Y1433549D03*
X663726Y1438933D03*
X672500Y1485000D03*
X667500Y1476250D03*
X707937Y57400D03*
X687700Y79300D03*
X692250Y74000D03*
X710000Y44500D03*
X707937Y73750D03*
X701300Y147700D03*
X690000Y148000D03*
X707937Y132800D03*
X693112Y342443D03*
X689172Y319945D03*
X698300Y519750D03*
X681000Y532500D03*
X690116Y535877D03*
X698100Y515100D03*
X707800Y520800D03*
X703200Y512000D03*
X704000Y600000D03*
X757300Y582800D03*
X690000Y600500D03*
X707900Y585200D03*
X749541Y717011D03*
X685500Y773631D03*
X680500Y790616D03*
X758562Y925283D03*
X675790Y861395D03*
X740364Y901060D03*
X758250Y1043000D03*
X707800Y1038200D03*
X698300Y972750D03*
X681000Y985500D03*
X690141Y989210D03*
X698000Y968300D03*
X707450Y973600D03*
X704000Y1053000D03*
X690000Y1053500D03*
X745367Y1239122D03*
X703411Y1387198D03*
X744132Y1426834D03*
X719000Y1453500D03*
X701000Y1438000D03*
X708500Y1438500D03*
X706000Y1453500D03*
X684750Y1435250D03*
X692750Y1435500D03*
X673500Y1448500D03*
X687900Y1471800D03*
X704000Y1469800D03*
X705890Y1446000D03*
X676500Y1472150D03*
X698500Y1431000D03*
X673964Y1434848D03*
X734032Y1465634D03*
X705500Y1463000D03*
X711363Y1458500D03*
X746064Y1494250D03*
X752132Y1450534D03*
X745406Y1486450D03*
X750232Y1472534D03*
X739532Y1430734D03*
X730332Y1457534D03*
X748732Y1460134D03*
X845968Y380023D03*
X842786Y374795D03*
X836451Y444751D03*
X844585Y451535D03*
X832417Y459017D03*
X829490Y657790D03*
X830990Y652690D03*
X829490Y647190D03*
X816068Y625673D03*
X796484Y648490D03*
X800684Y652390D03*
X805128Y646475D03*
X862500Y760000D03*
X817373Y744099D03*
X816104Y679776D03*
X806535Y676210D03*
X831000Y817600D03*
X861986Y804305D03*
X832500Y812500D03*
X830000Y807000D03*
X824500Y775000D03*
X824000Y769000D03*
X863100Y765200D03*
X862600Y769500D03*
X824500Y780500D03*
X819870Y932430D03*
X824970Y933930D03*
X830300Y932470D03*
X832000Y887000D03*
Y881500D03*
X796396Y879084D03*
X785560Y876549D03*
X844940Y915701D03*
X768449Y929466D03*
X769130Y919152D03*
X853398Y914258D03*
X860219Y912294D03*
X833500Y895500D03*
X859200Y891900D03*
X830470Y970430D03*
X822430Y968470D03*
X834871Y966706D03*
X814330Y1026361D03*
X810751Y1028560D03*
X797473Y1041318D03*
X844120Y974180D03*
X779222Y1116604D03*
X802162Y1075032D03*
X771236Y1096959D03*
X810000Y1327000D03*
X810500Y1377000D03*
X817277Y1402673D03*
X847000Y1407000D03*
X838500D03*
X852493Y1392918D03*
X945656Y547005D03*
X951860Y524737D03*
X951739Y530020D03*
X951915Y556600D03*
X866276Y650103D03*
X865530Y655230D03*
X892391Y622635D03*
X898676Y631324D03*
X865945Y643688D03*
X875007Y601293D03*
X916951Y757250D03*
X917600Y778500D03*
X955482Y772968D03*
Y778168D03*
Y767768D03*
X917700Y774200D03*
Y769200D03*
X946167Y853833D03*
X952500Y854500D03*
X957095Y854128D03*
X935250Y854000D03*
X940000D03*
X869000Y807000D03*
X867040Y815040D03*
X883750Y822250D03*
X874562Y825063D03*
X913597Y800899D03*
X906008Y799372D03*
X917211Y793314D03*
X908543Y792632D03*
X917211Y788194D03*
X917600Y783500D03*
X896283Y829425D03*
X886342Y834927D03*
X888100Y827700D03*
X880209Y831210D03*
X920461Y824079D03*
X917052Y831472D03*
X953742Y818977D03*
X941564Y821964D03*
X920170Y849500D03*
X925073Y840417D03*
X909940Y871500D03*
X918380Y911780D03*
X913000Y911500D03*
X923645Y911630D03*
X915250Y870750D03*
X920712Y870212D03*
X867700Y873500D03*
Y878200D03*
X867350Y883000D03*
X895346Y871309D03*
X900346D03*
X902749Y864327D03*
X898596Y858067D03*
X954208Y894134D03*
X949371Y898442D03*
X923468Y875044D03*
X940499Y905125D03*
X951500Y1222500D03*
X943500Y1221000D03*
X899919Y1176183D03*
X934200Y1190700D03*
X934271Y1198029D03*
X942955Y1200945D03*
X940168Y1211332D03*
X868900Y1192600D03*
X885118Y1202182D03*
X931900Y1206220D03*
X927500Y1211340D03*
X933200Y1216460D03*
X869937Y1395977D03*
X953652Y1420748D03*
X1026521Y387770D03*
X1036100Y410500D03*
X1045300Y420400D03*
X1033200Y423228D03*
X1017500Y426131D03*
X1047900Y432500D03*
X1041600Y435700D03*
X980100Y413700D03*
X1005846Y429434D03*
X1016557Y437230D03*
X995633Y547651D03*
X1004460Y533819D03*
X981500Y512300D03*
X984200Y539000D03*
X1015143Y577288D03*
X1003166Y574208D03*
X1011037Y736868D03*
X1015618Y700908D03*
X1019284Y721708D03*
X1023243Y732861D03*
X1028089Y707561D03*
X1032654Y697436D03*
X979107Y839078D03*
X974163Y839165D03*
X983000Y837500D03*
X989120D03*
X1005450Y849166D03*
X999500Y849500D03*
X1033807Y847865D03*
X989933Y872000D03*
X982500Y871400D03*
X971982Y873647D03*
X983311Y904195D03*
X978033Y902083D03*
X972854Y900520D03*
X964170Y895500D03*
X993483Y899206D03*
X1039500Y878500D03*
X1004300Y889275D03*
X1009800Y887100D03*
X1016400Y886500D03*
X1021500D03*
X1028500Y862000D03*
X1003000Y916000D03*
X1025500Y919500D03*
X1008739Y1096000D03*
X1028500Y1118601D03*
X965500Y1128000D03*
X1012800Y1122100D03*
X1002671Y1124700D03*
X977643Y1132490D03*
X1007431Y1122900D03*
X987300Y1179800D03*
X982172Y1176631D03*
X959500Y1221000D03*
X970500Y1205000D03*
X972000Y1223400D03*
Y1201000D03*
X970500Y1197000D03*
X967500Y1221000D03*
X972000Y1209000D03*
X970500Y1213000D03*
X963500Y1222500D03*
X1035882Y1327084D03*
X981700Y1315900D03*
X1045536Y1316578D03*
X975332Y1239578D03*
X1035676Y1383286D03*
X1036877Y1356115D03*
X1008443Y1425899D03*
X1015943Y1426399D03*
X1035100Y1397300D03*
X970552Y1421448D03*
X971169Y1426832D03*
X992800Y1422300D03*
X1000193Y1423399D03*
X979900Y1426800D03*
X1005943Y1418899D03*
X987600Y1425200D03*
X994884Y1393370D03*
X1049437Y1367213D03*
X1048400Y1339700D03*
X1036918Y1391589D03*
X1052485Y1421680D03*
X1018943Y1438899D03*
X979599Y1436399D03*
X995617Y1459516D03*
X1021618Y1460000D03*
X1013333Y1433899D03*
X979179Y1450158D03*
X1015550Y1496214D03*
X1028650Y1494714D03*
X1039450Y1501914D03*
X1037350Y1487714D03*
X1046850Y1485514D03*
X1050050Y1496014D03*
X966465Y1454578D03*
X966438Y1450158D03*
X1015443Y1452399D03*
X1016943Y1446320D03*
X973617Y1445912D03*
Y1440912D03*
X1035943Y1436649D03*
X1067872Y422624D03*
X1074400Y419124D03*
X1120959Y621993D03*
X1063591Y1008944D03*
X1056428Y998612D03*
X1059569Y1017555D03*
X1093332Y1037457D03*
X1124848Y1034859D03*
X1087100Y1304820D03*
X1086062Y1294580D03*
X1085962Y1309495D03*
X1055536Y1393731D03*
X1063920Y1385019D03*
X1130112Y1374773D03*
X1123037Y1374473D03*
X1111012Y1391273D03*
X1109612Y1371600D03*
Y1395273D03*
X1111112Y1399273D03*
X1114112Y1374773D03*
X1109612Y1387273D03*
X1111112Y1383273D03*
X1118301Y1374458D03*
X1138112Y1375273D03*
X1100300Y1359247D03*
X1133412Y1407173D03*
X1141554Y1399660D03*
X1147312Y1387193D03*
X1147512Y1382073D03*
X1144564Y1392821D03*
X1140175Y1389710D03*
X1140512Y1381273D03*
X1112673Y1500348D03*
X1242718Y335091D03*
X1238778Y312593D03*
X1234254Y442080D03*
X1216078Y465349D03*
X1232660Y453858D03*
X1188800Y507600D03*
X1216040Y625269D03*
X1207265Y709641D03*
X1212703Y758435D03*
X1206937Y755002D03*
X1214657Y681090D03*
X1232675Y738300D03*
X1217111Y829350D03*
X1242718Y820846D03*
X1238778Y798348D03*
X1216569Y819000D03*
X1189224Y912756D03*
X1188509Y918850D03*
X1160314Y1032608D03*
X1223634Y1052998D03*
X1211764Y1320310D03*
X1172318Y1320640D03*
X1218529Y1242316D03*
X1197394Y1298415D03*
X1230600D03*
X1202394D03*
X1235600D03*
X1192394D03*
X1225600D03*
X1202394Y1335151D03*
X1235600D03*
X1192394D03*
X1225600D03*
X1187394D03*
X1220600D03*
X1197394D03*
X1230600D03*
X1212460Y1422825D03*
X1209500Y1397433D03*
X1306950Y59950D03*
X1312100Y58300D03*
X1313000Y41750D03*
X1307000Y166100D03*
X1257533Y126350D03*
X1324900Y154100D03*
X1310500Y133000D03*
X1334250Y104300D03*
X1257000Y355500D03*
X1261060Y300000D03*
X1338423Y429770D03*
X1248784Y442826D03*
X1317000Y517000D03*
X1336500Y533500D03*
X1306800Y525500D03*
X1324500Y533500D03*
X1317000Y508250D03*
X1307100Y618800D03*
X1257500Y579050D03*
X1334000Y616500D03*
X1310500Y586000D03*
X1340324Y928894D03*
X1257100Y1031750D03*
X1310500Y1038500D03*
X1317000Y969500D03*
X1337500Y986000D03*
X1307850Y977800D03*
X1324500Y986000D03*
X1317000Y960750D03*
X1307100Y1071600D03*
X1334000Y1069000D03*
X1305500Y1413500D03*
X1324000Y1412600D03*
X1281624Y1425618D03*
X1277624Y1416318D03*
X1279484Y1471500D03*
X1255974Y1484800D03*
X1259374Y1501400D03*
X1269974Y1469300D03*
X1251574Y1490800D03*
X1270574Y1493300D03*
X1262774Y1449300D03*
X1257874Y1450500D03*
X1252274Y1477000D03*
X1270674Y1479500D03*
X1431300Y72150D03*
X1431100Y166000D03*
X1381756Y126350D03*
X1434500Y133000D03*
X1364600Y189600D03*
X1366931Y359435D03*
X1362991Y336937D03*
X1342880Y363931D03*
X1358498Y307500D03*
X1431350Y525000D03*
X1344024Y483916D03*
X1431300Y618900D03*
X1381600Y579200D03*
X1434500Y586000D03*
X1350982Y737700D03*
X1341324Y829350D03*
X1366931Y820844D03*
X1362991Y798346D03*
X1354742Y764100D03*
X1381500Y1031800D03*
X1434500Y1038500D03*
X1431350Y978200D03*
X1431313Y1071600D03*
X1341268Y1326727D03*
X1386424Y1415469D03*
X1365374Y1412500D03*
X1441000Y64000D03*
X1460500Y80500D03*
X1441200Y68200D03*
X1441000Y55250D03*
X1505968Y126350D03*
X1458000Y163500D03*
X1449286Y109468D03*
X1453052Y199552D03*
X1491143Y364938D03*
X1487203Y342440D03*
X1464994Y366244D03*
X1478954Y299400D03*
X1462350Y428169D03*
X1441000Y517000D03*
X1460500Y533500D03*
X1448500D03*
X1441000Y508250D03*
X1465195Y482118D03*
X1449416Y562671D03*
X1505900Y578800D03*
X1458000Y616500D03*
X1465536Y829350D03*
X1491143Y821350D03*
X1487203Y798852D03*
X1464994Y819000D03*
X1476400Y827900D03*
X1472646Y930795D03*
X1505700Y1031850D03*
X1441000Y969500D03*
X1461500Y986000D03*
X1448500D03*
X1441000Y960750D03*
X1458000Y1069000D03*
X1483629Y1240035D03*
X1562500Y50500D03*
X1576800Y69000D03*
X1555450Y59500D03*
X1563500Y61000D03*
X1562500Y41750D03*
X1555400Y166000D03*
X1568900Y148700D03*
X1559000Y133000D03*
X1615356Y363164D03*
X1611416Y340666D03*
X1589207Y366244D03*
X1603167Y304800D03*
X1578333Y431523D03*
X1587023Y474261D03*
X1565500Y517000D03*
X1585000Y533500D03*
X1555450Y524900D03*
X1573000Y533500D03*
X1565500Y508250D03*
X1555500Y618800D03*
X1582500Y616500D03*
X1559000Y586000D03*
X1589749Y829350D03*
X1615356Y822490D03*
X1611416Y799992D03*
X1597607Y763144D03*
X1600607Y824639D03*
X1607884Y925219D03*
X1559000Y1038500D03*
X1565500Y969500D03*
X1586000Y986000D03*
X1555750Y978600D03*
X1573000Y986000D03*
X1565500Y960750D03*
X1574019Y1015221D03*
X1555525Y1071600D03*
X1582500Y1069000D03*
X1689500Y64000D03*
X1709000Y80500D03*
X1679600Y72500D03*
X1697000Y80500D03*
X1689500Y55250D03*
X1679600Y166100D03*
X1630181Y126350D03*
X1706500Y163500D03*
X1683000Y133000D03*
X1697942Y109938D03*
X1720159Y475807D03*
X1721381Y411596D03*
X1717859Y460107D03*
X1711909Y470207D03*
X1711199Y453177D03*
X1706359Y441207D03*
X1689500Y517000D03*
X1709000Y533500D03*
X1680050Y525200D03*
X1697000Y533500D03*
X1689500Y508250D03*
X1701720Y497999D03*
X1698111Y562671D03*
X1679488Y618800D03*
X1630100Y579050D03*
X1706500Y616500D03*
X1683000Y586000D03*
X1713961Y829350D03*
X1629800Y1031850D03*
X1683000Y1038500D03*
X1689500Y969500D03*
X1709000Y986000D03*
X1679650Y978000D03*
X1697000Y986000D03*
X1689500Y960750D03*
X1697864Y1015165D03*
X1679738Y1071600D03*
X1706500Y1069000D03*
X1694626Y1414000D03*
X1712126Y1412600D03*
X1651906Y1447500D03*
X1659906Y1435500D03*
X1803200Y70600D03*
X1804800Y63100D03*
X1811800Y17700D03*
X1803900Y46100D03*
X1808200D03*
X1804000Y166100D03*
X1754300Y125900D03*
X1807000Y133000D03*
X1739568Y361896D03*
X1735628Y339398D03*
X1749650Y376854D03*
X1804600Y365600D03*
X1763791Y374891D03*
X1786451Y408530D03*
X1755159Y469723D03*
X1751774Y434652D03*
X1746959Y459107D03*
X1743359Y438057D03*
X1742758Y456059D03*
X1743959Y445807D03*
X1813500Y517000D03*
X1804050Y525100D03*
X1813500Y508250D03*
X1737859Y478707D03*
X1726859D03*
X1803700Y618800D03*
X1763000Y589000D03*
X1807000Y586000D03*
X1739568Y828517D03*
X1735628Y802019D03*
X1723619Y777600D03*
X1727379Y764235D03*
X1794563Y910125D03*
X1726771Y922050D03*
X1812263Y913025D03*
X1801263D03*
X1792263Y894425D03*
X1816263Y872375D03*
X1786313Y904525D03*
X1817739Y889758D03*
X1817863Y880125D03*
X1785603Y887495D03*
X1780763Y875525D03*
X1754300Y1031850D03*
X1807000Y1038500D03*
X1813500Y969500D03*
X1803750Y978100D03*
X1813500Y960750D03*
X1803950Y1071600D03*
X1729500Y1312000D03*
X1765596Y1414627D03*
X1748126Y1411500D03*
X1807626Y1485700D03*
X1797426Y1470400D03*
X1813826Y1471000D03*
X1800326Y1449600D03*
X1794426Y1450328D03*
X1799626Y1489800D03*
X1802526Y1471300D03*
X1874500Y73700D03*
X1822428Y77200D03*
X1878600Y24150D03*
X1862900Y34200D03*
X1862750Y73500D03*
X1818900Y88800D03*
X1878700Y19000D03*
X1876700Y42250D03*
X1835000Y25500D03*
Y20700D03*
X1874000Y146000D03*
X1830500Y163500D03*
X1860500Y147500D03*
X1878600Y132600D03*
X1830000Y101000D03*
X1836769Y355648D03*
X1839077Y346085D03*
X1852223Y303000D03*
X1876150Y525950D03*
X1853250Y522200D03*
X1833000Y533500D03*
X1857500Y558000D03*
X1859250Y531162D03*
X1821000Y533500D03*
X1849750Y518000D03*
X1858000Y510750D03*
X1860109Y497977D03*
X1874000Y599000D03*
X1830500Y616500D03*
X1860500Y600500D03*
X1878600Y585100D03*
X1846032Y746970D03*
X1838174Y829350D03*
X1863781Y821477D03*
X1859841Y798979D03*
X1849032Y827393D03*
X1866318Y948540D03*
X1829563Y904041D03*
X1827763Y869025D03*
X1821363Y893425D03*
X1871900Y988200D03*
X1878300Y1038300D03*
X1853250Y975200D03*
X1834000Y986000D03*
X1857500Y1010000D03*
X1859250Y983276D03*
X1821000Y986000D03*
X1849750Y971000D03*
X1858000Y963750D03*
X1874000Y1052000D03*
X1830500Y1069000D03*
X1860500Y1053500D03*
X1825059Y1476665D03*
X1825826Y1486750D03*
G54D43*
X90709Y1485118D03*
X80709D03*
X70709D03*
X711181D03*
X701181D03*
X691181D03*
X1237953D03*
X1227953D03*
X1217953D03*
X1858425D03*
X1848425D03*
X1838425D03*
G54D70*
X231674Y1421000D03*
X220074D03*
X1378174D03*
X1366574D03*
X1758440Y1420946D03*
X1746840D03*
G54D26*
X67800Y95000D03*
Y547500D03*
Y1000500D03*
X148100Y25200D03*
X191800Y547500D03*
X111228Y873035D03*
X192300Y1000500D03*
X209055Y435299D03*
X316300Y95000D03*
Y547500D03*
Y1000500D03*
X440300Y547500D03*
Y1000500D03*
X405800Y1408000D03*
X564800Y95000D03*
Y547500D03*
Y1000500D03*
X510800Y1474500D03*
X528500Y1448100D03*
X688800Y547500D03*
Y1000500D03*
X943800Y890000D03*
X1013300Y846500D03*
X1004107Y895075D03*
X993724Y891165D03*
X1117412Y1402773D03*
X1305100Y63900D03*
X1306900Y534000D03*
X1307900Y986200D03*
X1431400Y533900D03*
Y986400D03*
X1555500Y63300D03*
Y533800D03*
X1555800Y986600D03*
X1680100Y534100D03*
X1679700Y986300D03*
X1814900Y24800D03*
X1751824Y438717D03*
X1804100Y534100D03*
X1763300Y579500D03*
X1803800Y986200D03*
X1859300Y547500D03*
X1826228Y873035D03*
X1859300Y1000500D03*
G54D80*
X666250Y1485000D03*
X658750Y1481125D03*
Y1488875D03*
X954750Y908000D03*
X947250Y911875D03*
Y904125D03*
X957266Y1449272D03*
X949766Y1445397D03*
Y1453147D03*
X1024507Y929750D03*
X1017007Y933625D03*
Y925875D03*
G54D62*
X167716Y1495669D03*
X233858D03*
X548031D03*
X614173D03*
X1314960D03*
X1381102D03*
X1695275D03*
X1761417D03*
G54D44*
X118209Y81319D03*
Y76319D03*
Y71319D03*
Y66319D03*
Y61319D03*
Y56319D03*
Y51319D03*
Y176319D03*
Y171319D03*
Y166319D03*
Y161319D03*
Y156319D03*
Y151319D03*
Y146319D03*
Y141319D03*
Y136319D03*
Y131319D03*
Y126319D03*
Y121319D03*
Y116319D03*
Y111319D03*
Y106319D03*
Y569075D03*
Y564075D03*
Y559075D03*
Y534075D03*
Y529075D03*
Y524075D03*
Y519075D03*
Y514075D03*
Y509075D03*
Y504075D03*
Y629075D03*
Y624075D03*
Y619075D03*
Y614075D03*
Y609075D03*
Y604075D03*
Y599075D03*
Y594075D03*
Y589075D03*
Y584075D03*
Y579075D03*
Y574075D03*
Y1046831D03*
Y1041831D03*
Y1036831D03*
Y1031831D03*
Y1026831D03*
Y1021831D03*
Y1016831D03*
Y1011831D03*
Y986831D03*
Y981831D03*
Y976831D03*
Y971831D03*
Y966831D03*
Y961831D03*
Y956831D03*
Y1081831D03*
Y1076831D03*
Y1071831D03*
Y1066831D03*
Y1061831D03*
Y1056831D03*
Y1051831D03*
X242421Y81319D03*
Y76319D03*
Y71319D03*
Y66319D03*
Y61319D03*
Y56319D03*
Y51319D03*
Y176319D03*
Y171319D03*
Y166319D03*
Y161319D03*
Y156319D03*
Y151319D03*
Y146319D03*
Y141319D03*
Y136319D03*
Y131319D03*
Y126319D03*
Y121319D03*
Y116319D03*
Y111319D03*
Y106319D03*
Y569075D03*
Y564075D03*
Y559075D03*
Y534075D03*
Y529075D03*
Y524075D03*
Y519075D03*
Y514075D03*
Y509075D03*
Y504075D03*
Y629075D03*
Y624075D03*
Y619075D03*
Y614075D03*
Y609075D03*
Y604075D03*
Y599075D03*
Y594075D03*
Y589075D03*
Y584075D03*
Y579075D03*
Y574075D03*
Y1046831D03*
Y1041831D03*
Y1036831D03*
Y1031831D03*
Y1026831D03*
Y1021831D03*
Y1016831D03*
Y1011831D03*
Y986831D03*
Y981831D03*
Y976831D03*
Y971831D03*
Y966831D03*
Y961831D03*
Y956831D03*
Y1081831D03*
Y1076831D03*
Y1071831D03*
Y1066831D03*
Y1061831D03*
Y1056831D03*
Y1051831D03*
X366634Y81319D03*
Y76319D03*
Y71319D03*
Y66319D03*
Y61319D03*
Y56319D03*
Y51319D03*
Y176319D03*
Y171319D03*
Y166319D03*
Y161319D03*
Y156319D03*
Y151319D03*
Y146319D03*
Y141319D03*
Y136319D03*
Y131319D03*
Y126319D03*
Y121319D03*
Y116319D03*
Y111319D03*
Y106319D03*
Y569075D03*
Y564075D03*
Y559075D03*
Y534075D03*
Y529075D03*
Y524075D03*
Y519075D03*
Y514075D03*
Y509075D03*
Y504075D03*
Y629075D03*
Y624075D03*
Y619075D03*
Y614075D03*
Y609075D03*
Y604075D03*
Y599075D03*
Y594075D03*
Y589075D03*
Y584075D03*
Y579075D03*
Y574075D03*
Y1046831D03*
Y1041831D03*
Y1036831D03*
Y1031831D03*
Y1026831D03*
Y1021831D03*
Y1016831D03*
Y1011831D03*
Y986831D03*
Y981831D03*
Y976831D03*
Y971831D03*
Y966831D03*
Y961831D03*
Y956831D03*
Y1081831D03*
Y1076831D03*
Y1071831D03*
Y1066831D03*
Y1061831D03*
Y1056831D03*
Y1051831D03*
X490846Y81319D03*
Y76319D03*
Y71319D03*
Y66319D03*
Y61319D03*
Y56319D03*
Y51319D03*
Y176319D03*
Y171319D03*
Y166319D03*
Y161319D03*
Y156319D03*
Y151319D03*
Y146319D03*
Y141319D03*
Y136319D03*
Y131319D03*
Y126319D03*
Y121319D03*
Y116319D03*
Y111319D03*
Y106319D03*
Y569075D03*
Y564075D03*
Y559075D03*
Y534075D03*
Y529075D03*
Y524075D03*
Y519075D03*
Y514075D03*
Y509075D03*
Y504075D03*
Y629075D03*
Y624075D03*
Y619075D03*
Y614075D03*
Y609075D03*
Y604075D03*
Y599075D03*
Y594075D03*
Y589075D03*
Y584075D03*
Y579075D03*
Y574075D03*
Y1046831D03*
Y1041831D03*
Y1036831D03*
Y1031831D03*
Y1026831D03*
Y1021831D03*
Y1016831D03*
Y1011831D03*
Y986831D03*
Y981831D03*
Y976831D03*
Y971831D03*
Y966831D03*
Y961831D03*
Y956831D03*
Y1081831D03*
Y1076831D03*
Y1071831D03*
Y1066831D03*
Y1061831D03*
Y1056831D03*
Y1051831D03*
X615059Y81319D03*
Y76319D03*
Y71319D03*
Y66319D03*
Y61319D03*
Y56319D03*
Y51319D03*
Y176319D03*
Y171319D03*
Y166319D03*
Y161319D03*
Y156319D03*
Y151319D03*
Y146319D03*
Y141319D03*
Y136319D03*
Y131319D03*
Y126319D03*
Y121319D03*
Y116319D03*
Y111319D03*
Y106319D03*
Y569075D03*
Y564075D03*
Y559075D03*
Y534075D03*
Y529075D03*
Y524075D03*
Y519075D03*
Y514075D03*
Y509075D03*
Y504075D03*
Y629075D03*
Y624075D03*
Y619075D03*
Y614075D03*
Y609075D03*
Y604075D03*
Y599075D03*
Y594075D03*
Y589075D03*
Y584075D03*
Y579075D03*
Y574075D03*
Y1046831D03*
Y1041831D03*
Y1036831D03*
Y1031831D03*
Y1026831D03*
Y1021831D03*
Y1016831D03*
Y1011831D03*
Y986831D03*
Y981831D03*
Y976831D03*
Y971831D03*
Y966831D03*
Y961831D03*
Y956831D03*
Y1081831D03*
Y1076831D03*
Y1071831D03*
Y1066831D03*
Y1061831D03*
Y1056831D03*
Y1051831D03*
X739272Y81319D03*
Y76319D03*
Y71319D03*
Y66319D03*
Y61319D03*
Y56319D03*
Y51319D03*
Y176319D03*
Y171319D03*
Y166319D03*
Y161319D03*
Y156319D03*
Y151319D03*
Y146319D03*
Y141319D03*
Y136319D03*
Y131319D03*
Y126319D03*
Y121319D03*
Y116319D03*
Y111319D03*
Y106319D03*
Y569075D03*
Y564075D03*
Y559075D03*
Y534075D03*
Y529075D03*
Y524075D03*
Y519075D03*
Y514075D03*
Y509075D03*
Y504075D03*
Y629075D03*
Y624075D03*
Y619075D03*
Y614075D03*
Y609075D03*
Y604075D03*
Y599075D03*
Y594075D03*
Y589075D03*
Y584075D03*
Y579075D03*
Y574075D03*
Y1046831D03*
Y1041831D03*
Y1036831D03*
Y1031831D03*
Y1026831D03*
Y1021831D03*
Y1016831D03*
Y1011831D03*
Y986831D03*
Y981831D03*
Y976831D03*
Y971831D03*
Y966831D03*
Y961831D03*
Y956831D03*
Y1081831D03*
Y1076831D03*
Y1071831D03*
Y1066831D03*
Y1061831D03*
Y1056831D03*
Y1051831D03*
X1288878Y81319D03*
Y76319D03*
Y71319D03*
Y66319D03*
Y61319D03*
Y56319D03*
Y51319D03*
Y176319D03*
Y171319D03*
Y166319D03*
Y161319D03*
Y156319D03*
Y151319D03*
Y146319D03*
Y141319D03*
Y136319D03*
Y131319D03*
Y126319D03*
Y121319D03*
Y116319D03*
Y111319D03*
Y106319D03*
Y569075D03*
Y564075D03*
Y559075D03*
Y534075D03*
Y529075D03*
Y524075D03*
Y519075D03*
Y514075D03*
Y509075D03*
Y504075D03*
Y629075D03*
Y624075D03*
Y619075D03*
Y614075D03*
Y609075D03*
Y604075D03*
Y599075D03*
Y594075D03*
Y589075D03*
Y584075D03*
Y579075D03*
Y574075D03*
Y1046831D03*
Y1041831D03*
Y1036831D03*
Y1031831D03*
Y1026831D03*
Y1021831D03*
Y1016831D03*
Y1011831D03*
Y986831D03*
Y981831D03*
Y976831D03*
Y971831D03*
Y966831D03*
Y961831D03*
Y956831D03*
Y1081831D03*
Y1076831D03*
Y1071831D03*
Y1066831D03*
Y1061831D03*
Y1056831D03*
Y1051831D03*
X1413091Y81319D03*
Y76319D03*
Y71319D03*
Y66319D03*
Y61319D03*
Y56319D03*
Y51319D03*
Y176319D03*
Y171319D03*
Y166319D03*
Y161319D03*
Y156319D03*
Y151319D03*
Y146319D03*
Y141319D03*
Y136319D03*
Y131319D03*
Y126319D03*
Y121319D03*
Y116319D03*
Y111319D03*
Y106319D03*
Y569075D03*
Y564075D03*
Y559075D03*
Y534075D03*
Y529075D03*
Y524075D03*
Y519075D03*
Y514075D03*
Y509075D03*
Y504075D03*
Y629075D03*
Y624075D03*
Y619075D03*
Y614075D03*
Y609075D03*
Y604075D03*
Y599075D03*
Y594075D03*
Y589075D03*
Y584075D03*
Y579075D03*
Y574075D03*
Y1046831D03*
Y1041831D03*
Y1036831D03*
Y1031831D03*
Y1026831D03*
Y1021831D03*
Y1016831D03*
Y1011831D03*
Y986831D03*
Y981831D03*
Y976831D03*
Y971831D03*
Y966831D03*
Y961831D03*
Y956831D03*
Y1081831D03*
Y1076831D03*
Y1071831D03*
Y1066831D03*
Y1061831D03*
Y1056831D03*
Y1051831D03*
X1537303Y81319D03*
Y76319D03*
Y71319D03*
Y66319D03*
Y61319D03*
Y56319D03*
Y51319D03*
Y176319D03*
Y171319D03*
Y166319D03*
Y161319D03*
Y156319D03*
Y151319D03*
Y146319D03*
Y141319D03*
Y136319D03*
Y131319D03*
Y126319D03*
Y121319D03*
Y116319D03*
Y111319D03*
Y106319D03*
Y569075D03*
Y564075D03*
Y559075D03*
Y534075D03*
Y529075D03*
Y524075D03*
Y519075D03*
Y514075D03*
Y509075D03*
Y504075D03*
Y629075D03*
Y624075D03*
Y619075D03*
Y614075D03*
Y609075D03*
Y604075D03*
Y599075D03*
Y594075D03*
Y589075D03*
Y584075D03*
Y579075D03*
Y574075D03*
Y1046831D03*
Y1041831D03*
Y1036831D03*
Y1031831D03*
Y1026831D03*
Y1021831D03*
Y1016831D03*
Y1011831D03*
Y986831D03*
Y981831D03*
Y976831D03*
Y971831D03*
Y966831D03*
Y961831D03*
Y956831D03*
Y1081831D03*
Y1076831D03*
Y1071831D03*
Y1066831D03*
Y1061831D03*
Y1056831D03*
Y1051831D03*
X1661516Y81319D03*
Y76319D03*
Y71319D03*
Y66319D03*
Y61319D03*
Y56319D03*
Y51319D03*
Y176319D03*
Y171319D03*
Y166319D03*
Y161319D03*
Y156319D03*
Y151319D03*
Y146319D03*
Y141319D03*
Y136319D03*
Y131319D03*
Y126319D03*
Y121319D03*
Y116319D03*
Y111319D03*
Y106319D03*
Y569075D03*
Y564075D03*
Y559075D03*
Y534075D03*
Y529075D03*
Y524075D03*
Y519075D03*
Y514075D03*
Y509075D03*
Y504075D03*
Y629075D03*
Y624075D03*
Y619075D03*
Y614075D03*
Y609075D03*
Y604075D03*
Y599075D03*
Y594075D03*
Y589075D03*
Y584075D03*
Y579075D03*
Y574075D03*
Y1046831D03*
Y1041831D03*
Y1036831D03*
Y1031831D03*
Y1026831D03*
Y1021831D03*
Y1016831D03*
Y1011831D03*
Y986831D03*
Y981831D03*
Y976831D03*
Y971831D03*
Y966831D03*
Y961831D03*
Y956831D03*
Y1081831D03*
Y1076831D03*
Y1071831D03*
Y1066831D03*
Y1061831D03*
Y1056831D03*
Y1051831D03*
X1785728Y81319D03*
Y76319D03*
Y71319D03*
Y66319D03*
Y61319D03*
Y56319D03*
Y51319D03*
Y176319D03*
Y171319D03*
Y166319D03*
Y161319D03*
Y156319D03*
Y151319D03*
Y146319D03*
Y141319D03*
Y136319D03*
Y131319D03*
Y126319D03*
Y121319D03*
Y116319D03*
Y111319D03*
Y106319D03*
Y569075D03*
Y564075D03*
Y559075D03*
Y534075D03*
Y529075D03*
Y524075D03*
Y519075D03*
Y514075D03*
Y509075D03*
Y504075D03*
Y629075D03*
Y624075D03*
Y619075D03*
Y614075D03*
Y609075D03*
Y604075D03*
Y599075D03*
Y594075D03*
Y589075D03*
Y584075D03*
Y579075D03*
Y574075D03*
Y1046831D03*
Y1041831D03*
Y1036831D03*
Y1031831D03*
Y1026831D03*
Y1021831D03*
Y1016831D03*
Y1011831D03*
Y986831D03*
Y981831D03*
Y976831D03*
Y971831D03*
Y966831D03*
Y961831D03*
Y956831D03*
Y1081831D03*
Y1076831D03*
Y1071831D03*
Y1066831D03*
Y1061831D03*
Y1056831D03*
Y1051831D03*
X1909941Y81319D03*
Y76319D03*
Y71319D03*
Y66319D03*
Y61319D03*
Y56319D03*
Y51319D03*
Y176319D03*
Y171319D03*
Y166319D03*
Y161319D03*
Y156319D03*
Y151319D03*
Y146319D03*
Y141319D03*
Y136319D03*
Y131319D03*
Y126319D03*
Y121319D03*
Y116319D03*
Y111319D03*
Y106319D03*
Y569075D03*
Y564075D03*
Y559075D03*
Y534075D03*
Y529075D03*
Y524075D03*
Y519075D03*
Y514075D03*
Y509075D03*
Y504075D03*
Y629075D03*
Y624075D03*
Y619075D03*
Y614075D03*
Y609075D03*
Y604075D03*
Y599075D03*
Y594075D03*
Y589075D03*
Y584075D03*
Y579075D03*
Y574075D03*
Y1046831D03*
Y1041831D03*
Y1036831D03*
Y1031831D03*
Y1026831D03*
Y1021831D03*
Y1016831D03*
Y1011831D03*
Y986831D03*
Y981831D03*
Y976831D03*
Y971831D03*
Y966831D03*
Y961831D03*
Y956831D03*
Y1081831D03*
Y1076831D03*
Y1071831D03*
Y1066831D03*
Y1061831D03*
Y1056831D03*
Y1051831D03*
G54D35*
X93500Y136500D03*
Y125500D03*
Y589000D03*
Y578000D03*
Y1042000D03*
Y1031000D03*
X217500Y136500D03*
Y125500D03*
Y589000D03*
Y578000D03*
X218000Y1042000D03*
Y1031000D03*
X342000Y136500D03*
Y125500D03*
Y589000D03*
Y578000D03*
Y1042000D03*
Y1031000D03*
X466000Y136500D03*
Y125500D03*
Y589000D03*
Y578000D03*
Y1042000D03*
Y1031000D03*
X590500Y136500D03*
Y125500D03*
Y589000D03*
Y578000D03*
Y1042000D03*
Y1031000D03*
X714500Y136500D03*
Y125500D03*
Y589000D03*
Y578000D03*
Y1042000D03*
Y1031000D03*
X1308500Y150500D03*
Y139500D03*
Y603500D03*
Y592500D03*
Y1045000D03*
Y1056000D03*
X1432500Y150500D03*
Y139500D03*
Y603500D03*
Y592500D03*
Y1045000D03*
Y1056000D03*
X1557000Y150500D03*
Y139500D03*
Y603500D03*
Y592500D03*
Y1045000D03*
Y1056000D03*
X1681000Y150500D03*
Y139500D03*
Y603500D03*
Y592500D03*
Y1045000D03*
Y1056000D03*
X1805000Y150500D03*
Y139500D03*
Y603500D03*
Y592500D03*
Y1045000D03*
Y1056000D03*
X1885000Y136000D03*
Y125000D03*
Y589000D03*
Y578000D03*
Y1042000D03*
Y1031000D03*
G54D17*
X60000Y69800D03*
Y522300D03*
X81700Y901880D03*
X77563Y901825D03*
X60000Y975300D03*
X131600Y122700D03*
X179527Y464144D03*
X175390Y464089D03*
X184000Y522300D03*
X184500Y975300D03*
X138974Y1425700D03*
X149374Y1453800D03*
Y1435300D03*
X207000Y73800D03*
X217000Y41800D03*
X254900Y122900D03*
X308500Y69800D03*
X379500Y122900D03*
X308500Y522300D03*
Y975300D03*
X454000Y77200D03*
X465500Y41800D03*
X432500Y522300D03*
Y975300D03*
X557000Y69800D03*
X503900Y122800D03*
X557000Y522300D03*
Y975300D03*
X502999Y1448232D03*
X628000Y122800D03*
X583550Y512850D03*
X655795Y1426219D03*
X628500Y1461300D03*
X704000Y73800D03*
X714000Y41800D03*
X707800Y513500D03*
X681000Y522300D03*
X752200Y575600D03*
X681000Y975300D03*
X676500Y1476300D03*
X841939Y386415D03*
X846939D03*
X822470Y924230D03*
Y974230D03*
X830470D03*
X839970Y966470D03*
X955000Y544400D03*
X952100Y516600D03*
X922100Y757300D03*
X948500Y845800D03*
X953000D03*
X911080Y860670D03*
X918380Y915714D03*
X914260Y915670D03*
X951500Y1226300D03*
X868900Y1184800D03*
X888000Y1193900D03*
X986200Y544300D03*
X983300Y518600D03*
X966093Y845800D03*
X993942Y876100D03*
X976242Y877800D03*
X980442Y876100D03*
X1000500Y907300D03*
X1005500D03*
X959500Y1226300D03*
X963238Y1414118D03*
X998325Y1464234D03*
X1013618Y1464165D03*
X1043606Y1444949D03*
X975438Y1450208D03*
X1122112Y1366573D03*
X1134112D03*
X1114112D03*
X1118112D03*
X1138112D03*
X1203394Y1340083D03*
X1222100D03*
X1236600D03*
X1232100D03*
X1217100D03*
X1183894D03*
X1188894D03*
X1198894D03*
X1203487Y1421241D03*
X1308000Y38300D03*
X1318000D03*
X1317800Y50600D03*
X1311700Y65700D03*
X1313700Y50600D03*
X1262600Y122900D03*
X1312000Y504800D03*
X1322000D03*
X1326500Y517300D03*
X1322000D03*
X1262600Y575600D03*
X1262400Y1028300D03*
X1312000Y957300D03*
X1322000D03*
X1326500Y969800D03*
X1322000D03*
X1296374Y1453800D03*
Y1435300D03*
X1436000Y51800D03*
X1387200Y122900D03*
X1436000Y504800D03*
X1386400Y575600D03*
X1387000Y1028400D03*
X1436000Y957300D03*
X1446000Y51800D03*
X1450500Y64300D03*
X1446000D03*
X1511400Y122900D03*
X1446000Y504800D03*
X1450500Y517300D03*
X1446000D03*
X1511200Y575600D03*
X1446000Y957300D03*
X1450500Y969800D03*
X1446000D03*
X1511400Y1028400D03*
X1557500Y38300D03*
X1567500D03*
X1572000Y50800D03*
X1563500Y65800D03*
X1567500Y50800D03*
X1560500Y504800D03*
X1570500D03*
X1575000Y517300D03*
X1570500D03*
X1560500Y957300D03*
X1570500D03*
X1575000Y969800D03*
X1570500D03*
X1684500Y51800D03*
X1694500D03*
X1699000Y64300D03*
X1694500D03*
X1635300Y122900D03*
X1722296Y467562D03*
X1718159Y467507D03*
X1684500Y504800D03*
X1694500D03*
X1699000Y517300D03*
X1694500D03*
X1634200Y575600D03*
X1635100Y1028400D03*
X1684500Y957300D03*
X1694500D03*
X1699000Y969800D03*
X1694500D03*
X1676626Y1453800D03*
Y1435300D03*
X1759600Y122900D03*
X1808500Y504800D03*
X1792563Y901825D03*
X1796700Y901880D03*
X1759300Y1028400D03*
X1808500Y957300D03*
X1884600Y42300D03*
X1862300Y26600D03*
X1818500Y504800D03*
X1823000Y517300D03*
X1818500D03*
X1853000Y507300D03*
X1848500D03*
X1843000Y537800D03*
X1818500Y957300D03*
X1823000Y969800D03*
X1818500D03*
X1875800Y984800D03*
X1853000Y960300D03*
X1848500D03*
X1843000Y990800D03*
G54D71*
X384055Y1330472D03*
Y1320472D03*
X354055Y1330472D03*
X364055D03*
X354055Y1320472D03*
X364055D03*
X324055Y1330472D03*
X334055D03*
X324055Y1320472D03*
X334055D03*
X304055Y1330472D03*
Y1320472D03*
X294055Y1330472D03*
Y1320472D03*
X384055Y1340472D03*
Y1350472D03*
X354055Y1340472D03*
Y1350472D03*
X364055Y1340472D03*
Y1350472D03*
X324055Y1340472D03*
Y1350472D03*
X334055Y1340472D03*
Y1350472D03*
X304055D03*
Y1340472D03*
X294055Y1350472D03*
Y1340472D03*
X474055Y1330472D03*
X484055D03*
X474055Y1320472D03*
X484055D03*
X444055Y1330472D03*
X454055D03*
X444055Y1320472D03*
X454055D03*
X414055Y1330472D03*
X424055D03*
X414055Y1320472D03*
X424055D03*
X394055Y1330472D03*
Y1320472D03*
X474055Y1340472D03*
Y1350472D03*
X484055Y1340472D03*
Y1350472D03*
X444055Y1340472D03*
Y1350472D03*
X454055Y1340472D03*
Y1350472D03*
X414055Y1340472D03*
Y1350472D03*
X424055Y1340472D03*
Y1350472D03*
X394055Y1340472D03*
Y1350472D03*
G54D53*
X111024Y188130D03*
Y640886D03*
Y1093642D03*
X235236Y188130D03*
Y640886D03*
Y1093642D03*
X359449Y188130D03*
Y640886D03*
Y1093642D03*
X483661Y188130D03*
Y640886D03*
Y1093642D03*
X607874Y188130D03*
Y640886D03*
Y1093642D03*
X732087Y188130D03*
Y640886D03*
Y1093642D03*
X1281693Y188130D03*
Y640886D03*
Y1093642D03*
X1405906Y188130D03*
Y640886D03*
Y1093642D03*
X1530118Y188130D03*
Y640886D03*
Y1093642D03*
X1654331Y188130D03*
Y640886D03*
Y1093642D03*
X1778543Y188130D03*
Y640886D03*
Y1093642D03*
X1902756Y188130D03*
Y640886D03*
Y1093642D03*
G54D18*
X72500Y63800D03*
Y516300D03*
Y969300D03*
X102263Y912325D03*
X162374Y1428000D03*
X180374Y1416800D03*
X162274Y1419400D03*
X180374Y1409150D03*
X139374Y1478300D03*
X105474Y1473285D03*
X215500Y73800D03*
X220000D03*
X202800Y37500D03*
X200090Y474589D03*
X196500Y516300D03*
X197000Y969300D03*
X321000Y63800D03*
Y516300D03*
Y969300D03*
X464000Y73800D03*
X468500D03*
X444400Y35800D03*
X435100Y118900D03*
X445000Y516300D03*
Y969300D03*
X569500Y63800D03*
Y516300D03*
Y969300D03*
X500000Y1465300D03*
X672000Y1422300D03*
X655795Y1436719D03*
X653000Y1481300D03*
X712500Y73800D03*
X717000D03*
X699600Y37400D03*
X693500Y516300D03*
Y969300D03*
X689000Y1422300D03*
X681000D03*
X703500Y1429300D03*
X680500Y1476300D03*
X730232Y1461319D03*
X752832Y1458319D03*
X860298Y410392D03*
X862766Y421192D03*
X850947Y410392D03*
X830470Y924230D03*
X826470D03*
X818470D03*
X826470Y974230D03*
X839970D03*
X834470D03*
X872137Y421192D03*
X950639Y547041D03*
X947587Y520682D03*
X871240Y635740D03*
X868500Y799600D03*
X957500Y845800D03*
X944000D03*
X935000D03*
X939500D03*
X927260Y915670D03*
X915580Y860670D03*
X922760Y915670D03*
X909760D03*
X924670Y860640D03*
X920170D03*
X955500Y1226300D03*
X947500D03*
X943500D03*
X869937Y1386929D03*
X944016Y1445572D03*
X991129Y547701D03*
X987333Y523068D03*
X962000Y845800D03*
X977570Y831728D03*
X973070D03*
X983070Y829790D03*
X1005450Y842060D03*
X1000950D03*
X1029600Y853600D03*
X985542Y876100D03*
X989742D03*
X972042Y877800D03*
X1030515Y883281D03*
X1033315Y890881D03*
X1039500Y883300D03*
X1048000Y890300D03*
X967500Y1226300D03*
X963500D03*
X1010943Y1417199D03*
X979443Y1411199D03*
X988443Y1410199D03*
X996443D03*
X963238Y1424618D03*
X1017618Y1464165D03*
X994271Y1464217D03*
X1021618Y1464165D03*
X1038303Y1444949D03*
X1040663Y1464441D03*
X1115825Y618543D03*
X1055500Y890300D03*
X1060118Y1381389D03*
X1126112Y1366573D03*
X1130112D03*
X1223730Y1289083D03*
X1235600D03*
X1230600D03*
X1190524D03*
X1197394D03*
X1202394D03*
X1241600Y1340083D03*
X1227100D03*
X1208394D03*
X1193894D03*
X1303500Y38300D03*
X1307500Y504800D03*
Y957300D03*
X1319500Y1416800D03*
Y1409150D03*
X1251874Y1480985D03*
X1431500Y51800D03*
Y504800D03*
Y957300D03*
X1553000Y38300D03*
X1556000Y504800D03*
Y957300D03*
X1680000Y51800D03*
Y504800D03*
Y957300D03*
X1707626Y1416800D03*
Y1409150D03*
X1652510Y1453300D03*
X1799100Y75100D03*
X1808500Y61000D03*
X1803400Y50400D03*
X1808300Y50500D03*
X1804000Y504800D03*
X1742859Y478007D03*
X1817263Y912325D03*
X1804000Y957300D03*
X1807676Y1478360D03*
X1880500Y42300D03*
X1872900D03*
X1874900Y21800D03*
X1863000Y507300D03*
Y960300D03*
G54D27*
X64200Y95000D03*
Y547500D03*
Y1000500D03*
X144500Y25200D03*
X188200Y547500D03*
X107628Y873035D03*
X188700Y1000500D03*
X205455Y435299D03*
X312700Y95000D03*
Y547500D03*
Y1000500D03*
X436700Y547500D03*
Y1000500D03*
X402200Y1408000D03*
X561200Y95000D03*
Y547500D03*
Y1000500D03*
X507200Y1474500D03*
X524900Y1448100D03*
X685200Y547500D03*
Y1000500D03*
X940200Y890000D03*
X1009700Y846500D03*
X1000507Y895075D03*
X990124Y891165D03*
X1113812Y1402773D03*
X1301500Y63900D03*
X1303300Y534000D03*
X1304300Y986200D03*
X1427800Y533900D03*
Y986400D03*
X1551900Y63300D03*
Y533800D03*
X1552200Y986600D03*
X1676500Y534100D03*
X1676100Y986300D03*
X1811300Y24800D03*
X1748224Y438717D03*
X1800500Y534100D03*
X1759700Y579500D03*
X1800200Y986200D03*
X1855700Y547500D03*
X1822628Y873035D03*
X1855700Y1000500D03*
G54D90*
X859113Y1290032D03*
Y1301000D03*
X871556Y1290030D03*
Y1300998D03*
X884056Y1290030D03*
Y1300998D03*
X901435Y1396353D03*
Y1385385D03*
X913935Y1396353D03*
Y1385385D03*
X888776Y1396385D03*
Y1385417D03*
X1023823Y379318D03*
Y368350D03*
G54D36*
X61800Y140500D03*
X54200D03*
X61800Y593000D03*
X54200D03*
X72490Y881867D03*
X80090D03*
X72490Y874206D03*
X80090D03*
X87194Y872375D03*
X94794D03*
X61800Y1046000D03*
X54200D03*
X86624Y1465850D03*
X94224D03*
X94324Y1473650D03*
X86724D03*
X185800Y140500D03*
X178200D03*
X170317Y444131D03*
X177917D03*
X170317Y436470D03*
X177917D03*
X185021Y434639D03*
X192621D03*
X185800Y593000D03*
X178200D03*
X186300Y1046000D03*
X178700D03*
X310300Y140500D03*
X302700D03*
X310300Y593000D03*
X302700D03*
X310300Y1046000D03*
X302700D03*
X434300Y140500D03*
X426700D03*
X434300Y593000D03*
X426700D03*
X434300Y1046000D03*
X426700D03*
X558800Y140500D03*
X551200D03*
X558800Y593000D03*
X551200D03*
X558800Y1046000D03*
X551200D03*
X682800Y140500D03*
X675200D03*
X682800Y593000D03*
X675200D03*
X682800Y1046000D03*
X675200D03*
X731350Y1486450D03*
X738950D03*
Y1494250D03*
X731350D03*
X817800Y1333000D03*
X810200D03*
X847295Y1392884D03*
X839695D03*
X839656Y1400536D03*
X847256D03*
X830342Y1402656D03*
X822742D03*
X817800Y1371500D03*
X810200D03*
X1049568Y1327989D03*
X1041968D03*
X1041818Y1391589D03*
X1049418D03*
Y1399389D03*
X1041818D03*
X1049568Y1355789D03*
X1041968D03*
X1049568Y1383589D03*
X1041968D03*
X1125673Y1493448D03*
X1118073D03*
X1234874Y1465500D03*
X1242474D03*
Y1473200D03*
X1234874D03*
X1713086Y447549D03*
X1720686D03*
X1713086Y439888D03*
X1720686D03*
X1727790Y438057D03*
X1735390D03*
X1787490Y881867D03*
X1795090D03*
X1787490Y874206D03*
X1795090D03*
X1802194Y872375D03*
X1809794D03*
X1853300Y140000D03*
X1845700D03*
X1853300Y593000D03*
X1845700D03*
X1853300Y1046000D03*
X1845700D03*
X1842026Y1473350D03*
X1834426D03*
X1834526Y1465600D03*
X1842126D03*
G54D45*
X111024Y27697D03*
Y199941D03*
Y480453D03*
Y652697D03*
Y933209D03*
Y1105453D03*
X235236Y27697D03*
Y199941D03*
Y480453D03*
Y652697D03*
Y933209D03*
Y1105453D03*
X359449Y27697D03*
Y199941D03*
Y480453D03*
Y652697D03*
Y933209D03*
Y1105453D03*
X483661Y27697D03*
Y199941D03*
Y480453D03*
Y652697D03*
Y933209D03*
Y1105453D03*
X607874Y27697D03*
Y199941D03*
Y480453D03*
Y652697D03*
Y933209D03*
Y1105453D03*
X732087Y27697D03*
Y199941D03*
Y480453D03*
Y652697D03*
Y933209D03*
Y1105453D03*
X957000Y1207500D03*
X1124612Y1388773D03*
X1281693Y27697D03*
Y199941D03*
Y480453D03*
Y652697D03*
Y933209D03*
Y1105453D03*
X1405906Y27697D03*
Y199941D03*
Y480453D03*
Y652697D03*
Y933209D03*
Y1105453D03*
X1530118Y27697D03*
Y199941D03*
Y480453D03*
Y652697D03*
Y933209D03*
Y1105453D03*
X1654331Y27697D03*
Y199941D03*
Y480453D03*
Y652697D03*
Y933209D03*
Y1105453D03*
X1778543Y27697D03*
Y199941D03*
Y480453D03*
Y652697D03*
Y933209D03*
Y1105453D03*
X1902756Y27697D03*
Y199941D03*
Y480453D03*
Y652697D03*
Y933209D03*
Y1105453D03*
G54D81*
X679950Y1446610D03*
Y1460390D03*
X700050D03*
Y1446610D03*
X987393Y1434509D03*
Y1448289D03*
X1007493D03*
Y1434509D03*
G54D54*
X173228Y122047D03*
X670079D03*
X1343701Y122046D03*
X1840551D03*
G54D63*
X111174Y1474560D03*
Y1472000D03*
Y1469440D03*
X118574D03*
Y1472000D03*
Y1474560D03*
X203300Y68060D03*
Y65500D03*
Y62940D03*
X210700D03*
Y65500D03*
Y68060D03*
X450300D03*
Y65500D03*
Y62940D03*
X457700D03*
Y65500D03*
Y68060D03*
X700300D03*
Y65500D03*
Y62940D03*
X707700D03*
Y65500D03*
Y68060D03*
X735932Y1459794D03*
Y1457234D03*
Y1454674D03*
X743332D03*
Y1457234D03*
Y1459794D03*
X1299800Y53060D03*
Y50500D03*
Y47940D03*
X1307200D03*
Y50500D03*
Y53060D03*
X1303800Y519560D03*
Y517000D03*
Y514440D03*
X1311200D03*
Y517000D03*
Y519560D03*
X1303800Y972060D03*
Y969500D03*
Y966940D03*
X1311200D03*
Y969500D03*
Y972060D03*
X1257374Y1478960D03*
Y1476400D03*
Y1473840D03*
X1264774D03*
Y1476400D03*
Y1478960D03*
X1427800Y66560D03*
Y64000D03*
Y61440D03*
X1435200D03*
Y64000D03*
Y66560D03*
X1427800Y519560D03*
Y517000D03*
Y514440D03*
X1435200D03*
Y517000D03*
Y519560D03*
X1427800Y972060D03*
Y969500D03*
Y966940D03*
X1435200D03*
Y969500D03*
Y972060D03*
X1549300Y53060D03*
Y50500D03*
Y47940D03*
X1556700D03*
Y50500D03*
Y53060D03*
X1552300Y519560D03*
Y517000D03*
Y514440D03*
X1559700D03*
Y517000D03*
Y519560D03*
X1552300Y972060D03*
Y969500D03*
Y966940D03*
X1559700D03*
Y969500D03*
Y972060D03*
X1676300Y66560D03*
Y64000D03*
Y61440D03*
X1683700D03*
Y64000D03*
Y66560D03*
X1676300Y519560D03*
Y517000D03*
Y514440D03*
X1683700D03*
Y517000D03*
Y519560D03*
X1676300Y972060D03*
Y969500D03*
Y966940D03*
X1683700D03*
Y969500D03*
Y972060D03*
X1808600Y75260D03*
Y72700D03*
Y70140D03*
X1816000D03*
Y72700D03*
Y75260D03*
X1800300Y519560D03*
Y517000D03*
Y514440D03*
X1807700D03*
Y517000D03*
Y519560D03*
X1800300Y972060D03*
Y969500D03*
Y966940D03*
X1807700D03*
Y969500D03*
Y972060D03*
X1866700Y516440D03*
Y519000D03*
Y521560D03*
X1859300D03*
Y519000D03*
Y516440D03*
X1866700Y969440D03*
Y972000D03*
Y974560D03*
X1859300D03*
Y972000D03*
Y969440D03*
G54D72*
X418505Y1423348D03*
X390221D03*
G54D19*
X72500Y67200D03*
Y519700D03*
Y972700D03*
X102263Y915725D03*
X180374Y1420200D03*
X162274Y1422800D03*
X180374Y1412550D03*
X139374Y1481700D03*
X162374Y1431400D03*
X105474Y1476685D03*
X215500Y77200D03*
X220000D03*
X202800Y40900D03*
X196500Y519700D03*
X200090Y477989D03*
X197000Y972700D03*
X321000Y67200D03*
Y519700D03*
Y972700D03*
X464000Y77200D03*
X468500D03*
X444400Y39200D03*
X435100Y122300D03*
X445000Y519700D03*
Y972700D03*
X569500Y67200D03*
Y519700D03*
Y972700D03*
X500000Y1468700D03*
X672000Y1425700D03*
X655795Y1440119D03*
X653000Y1484700D03*
X712500Y77200D03*
X717000D03*
X699600Y40800D03*
X693500Y519700D03*
Y972700D03*
X689000Y1425700D03*
X681000D03*
X680500Y1479700D03*
X703500Y1432700D03*
X730232Y1464719D03*
X752832Y1461719D03*
X860298Y413792D03*
X862766Y424592D03*
X850947Y413792D03*
X830470Y927630D03*
X826470D03*
X818470D03*
X826470Y977630D03*
X839970D03*
X834470D03*
X872137Y424592D03*
X950639Y550441D03*
X947587Y524082D03*
X871240Y639140D03*
X868500Y803000D03*
X957500Y849200D03*
X944000D03*
X935000D03*
X939500D03*
X927260Y919070D03*
X915580Y864070D03*
X922760Y919070D03*
X909760D03*
X924670Y864040D03*
X920170D03*
X955500Y1229700D03*
X947500D03*
X943500D03*
X869937Y1390329D03*
X944016Y1448972D03*
X991129Y551101D03*
X987333Y526468D03*
X962000Y849200D03*
X977570Y835128D03*
X973070D03*
X983070Y833190D03*
X1005450Y845460D03*
X1000950D03*
X1029600Y857000D03*
X985542Y879500D03*
X989742D03*
X972042Y881200D03*
X1030515Y886681D03*
X1033315Y894281D03*
X1039500Y886700D03*
X1048000Y893700D03*
X967500Y1229700D03*
X963500D03*
X1010943Y1420599D03*
X979443Y1414599D03*
X988443Y1413599D03*
X996443D03*
X963238Y1428018D03*
X1017618Y1467565D03*
X994271Y1467617D03*
X1021618Y1467565D03*
X1038303Y1448349D03*
X1040663Y1467841D03*
X1115825Y621943D03*
X1055500Y893700D03*
X1060118Y1384789D03*
X1126112Y1369973D03*
X1130112D03*
X1223730Y1292483D03*
X1235600D03*
X1230600D03*
X1190524D03*
X1197394D03*
X1202394D03*
X1241600Y1343483D03*
X1227100D03*
X1208394D03*
X1193894D03*
X1303500Y41700D03*
X1307500Y508200D03*
Y960700D03*
X1319500Y1420200D03*
Y1412550D03*
X1251874Y1484385D03*
X1431500Y55200D03*
Y508200D03*
Y960700D03*
X1553000Y41700D03*
X1556000Y508200D03*
Y960700D03*
X1680000Y55200D03*
Y508200D03*
Y960700D03*
X1707626Y1420200D03*
Y1412550D03*
X1652510Y1456700D03*
X1799100Y78500D03*
X1808500Y64400D03*
X1803400Y53800D03*
X1808300Y53900D03*
X1804000Y508200D03*
X1742859Y481407D03*
X1817263Y915725D03*
X1804000Y960700D03*
X1807676Y1481760D03*
X1880500Y45700D03*
X1872900D03*
X1874900Y25200D03*
X1863000Y510700D03*
Y963700D03*
G54D37*
X94000Y170300D03*
Y162700D03*
Y622800D03*
Y615200D03*
Y1075800D03*
Y1068200D03*
X218500Y170300D03*
Y162700D03*
Y622800D03*
Y615200D03*
Y1075800D03*
Y1068200D03*
X342500Y170300D03*
Y162700D03*
Y622800D03*
Y615200D03*
Y1075800D03*
Y1068200D03*
X467000Y170300D03*
Y162700D03*
Y622800D03*
Y615200D03*
Y1075800D03*
Y1068200D03*
X591000Y170300D03*
Y162700D03*
Y622800D03*
Y615200D03*
Y1075800D03*
Y1068200D03*
X715300Y170300D03*
Y162700D03*
Y622800D03*
Y615200D03*
Y1075800D03*
Y1068200D03*
X1007618Y1465065D03*
Y1472665D03*
X1305000Y173200D03*
Y180800D03*
X1313000Y173200D03*
Y180800D03*
X1305000Y626200D03*
Y633800D03*
X1313000Y626200D03*
Y633800D03*
X1305000Y1078700D03*
Y1086300D03*
X1313000Y1078700D03*
Y1086300D03*
X1429000Y173200D03*
Y180800D03*
X1437000Y173200D03*
Y180800D03*
X1429000Y626200D03*
Y633800D03*
X1437000Y626200D03*
Y633800D03*
X1429000Y1078700D03*
Y1086300D03*
X1437000Y1078700D03*
Y1086300D03*
X1553500Y173200D03*
Y180800D03*
X1561500Y173200D03*
Y180800D03*
X1553500Y626200D03*
Y633800D03*
X1561500Y626200D03*
Y633800D03*
X1553500Y1078700D03*
Y1086300D03*
X1561500Y1078700D03*
Y1086300D03*
X1677500Y173200D03*
Y180800D03*
X1685500Y173200D03*
Y180800D03*
X1677500Y626200D03*
Y633800D03*
X1685500Y626200D03*
Y633800D03*
X1677500Y1078700D03*
Y1086300D03*
X1685500Y1078700D03*
Y1086300D03*
X1801500Y173200D03*
Y180800D03*
X1809500Y173200D03*
Y180800D03*
X1801500Y626200D03*
Y633800D03*
X1809500Y626200D03*
Y633800D03*
X1801500Y1078700D03*
Y1086300D03*
X1809500Y1078700D03*
Y1086300D03*
X1886000Y169800D03*
Y162200D03*
X1885800Y622800D03*
Y615200D03*
X1885963Y1075886D03*
Y1068286D03*
G54D64*
X153524Y1464000D03*
X140224D03*
X153524Y1445500D03*
X140224D03*
X1300524Y1464000D03*
X1287224D03*
X1300524Y1445500D03*
X1287224D03*
X1680776Y1464000D03*
X1667476D03*
X1680776Y1445500D03*
X1667476D03*
G54D82*
X680250Y1448579D03*
Y1450547D03*
Y1452516D03*
Y1454484D03*
Y1456453D03*
Y1458421D03*
X699750D03*
Y1456453D03*
Y1454484D03*
Y1452516D03*
Y1450547D03*
Y1448579D03*
X987693Y1436478D03*
Y1438446D03*
Y1440415D03*
Y1442383D03*
Y1444352D03*
Y1446320D03*
X1007193D03*
Y1444352D03*
Y1442383D03*
Y1440415D03*
Y1438446D03*
Y1436478D03*
G54D91*
X809631Y1320085D03*
Y1315085D03*
Y1310085D03*
Y1305085D03*
X810101Y1362591D03*
Y1357591D03*
Y1352591D03*
Y1347591D03*
X809880Y1400259D03*
Y1395259D03*
Y1390259D03*
Y1385259D03*
X1028118Y1327489D03*
Y1322489D03*
Y1317489D03*
Y1312489D03*
Y1383089D03*
Y1378089D03*
Y1373089D03*
Y1368089D03*
Y1355289D03*
Y1350289D03*
Y1345289D03*
Y1340289D03*
G54D55*
X127600Y126200D03*
X158474Y1422900D03*
X153374Y1457300D03*
Y1438800D03*
X250900Y126400D03*
X375500D03*
X440849Y118900D03*
X499900Y126300D03*
X624000D03*
X668000Y1425800D03*
X672500Y1479800D03*
X748200Y579100D03*
X698500Y1425800D03*
X685000D03*
X693000D03*
X735232Y1447134D03*
X990100Y833300D03*
X1026515Y886781D03*
X1000443Y1413699D03*
X992443D03*
X975443Y1414699D03*
X1005943Y1413699D03*
X971438Y1453708D03*
X1035943Y1431699D03*
X1207440Y1424654D03*
X1266600Y126400D03*
Y579100D03*
X1266400Y1031800D03*
X1300374Y1457300D03*
Y1438800D03*
X1253374Y1466700D03*
X1391200Y126400D03*
X1390400Y579100D03*
X1391000Y1031900D03*
X1515400Y126400D03*
X1515200Y579100D03*
X1515400Y1031900D03*
X1639300Y126400D03*
X1638200Y579100D03*
X1639100Y1031900D03*
X1680626Y1457300D03*
Y1438800D03*
X1763600Y126400D03*
X1763300Y1031900D03*
X1790226Y1465900D03*
X1879800Y988300D03*
G54D28*
X56700Y100500D03*
Y553000D03*
Y1006000D03*
X195200Y82500D03*
X180700Y553000D03*
X137200Y579000D03*
X107656Y878062D03*
X137200Y1032000D03*
X181200Y1006000D03*
X205483Y440326D03*
X261200Y579000D03*
X260900Y1032000D03*
X223355Y1434029D03*
X305200Y100500D03*
Y553000D03*
X385700Y579000D03*
X305200Y1006000D03*
X385700Y1032000D03*
X429200Y553000D03*
Y1006000D03*
X553700Y100500D03*
Y553000D03*
X509700Y579000D03*
Y1032000D03*
X553700Y1006000D03*
X634200Y579000D03*
Y1032000D03*
X692200Y82500D03*
X748200Y126500D03*
X677700Y553000D03*
Y1006000D03*
X749500Y1032000D03*
X692200Y1476000D03*
X710700Y1449700D03*
X837190Y645690D03*
X834900Y804500D03*
X867000Y774500D03*
X927700Y763820D03*
X867700Y887500D03*
X873400Y1188400D03*
X896500Y1191700D03*
X978081Y559671D03*
X976647Y533383D03*
X1008041Y895045D03*
X1018333Y892965D03*
X964500Y1193500D03*
X1330700Y113500D03*
X1331700Y566500D03*
Y1019000D03*
X1432200Y81000D03*
X1370429Y1434045D03*
X1455700Y113500D03*
Y566500D03*
Y1019000D03*
X1601100Y133000D03*
X1580200Y566500D03*
Y1019000D03*
X1679600Y81000D03*
X1704200Y113500D03*
Y566500D03*
Y1019000D03*
X1748252Y443744D03*
X1750574Y1434109D03*
X1878200Y81500D03*
X1862700Y82000D03*
X1863900Y42100D03*
X1827200Y113500D03*
X1828200Y566500D03*
X1876100Y534600D03*
X1848200Y553000D03*
X1822656Y878062D03*
X1828200Y1019000D03*
X1848200Y1006000D03*
G54D46*
X111024Y39508D03*
Y492264D03*
Y945020D03*
X235236Y39508D03*
Y492264D03*
Y945020D03*
X359449Y39508D03*
Y492264D03*
Y945020D03*
X483661Y39508D03*
Y492264D03*
Y945020D03*
X607874Y39508D03*
Y492264D03*
Y945020D03*
X732087Y39508D03*
Y492264D03*
Y945020D03*
X1281693Y39508D03*
Y492264D03*
Y945020D03*
X1405906Y39508D03*
Y492264D03*
Y945020D03*
X1530118Y39508D03*
Y492264D03*
Y945020D03*
X1654331Y39508D03*
Y492264D03*
Y945020D03*
X1778543Y39508D03*
Y492264D03*
Y945020D03*
X1902756Y39508D03*
Y492264D03*
Y945020D03*
G54D73*
X462000Y1382985D03*
Y1372985D03*
Y1362985D03*
X474000Y1382985D03*
Y1372985D03*
Y1362985D03*
X426000D03*
X450000Y1372985D03*
Y1382985D03*
X414000Y1372985D03*
X450000Y1362985D03*
X438000Y1372985D03*
X414000Y1362985D03*
X438000D03*
X426000Y1372985D03*
X438000Y1382985D03*
X414000D03*
X426000D03*
X498000Y1332985D03*
X510000Y1344485D03*
X498000Y1352985D03*
X522000Y1344485D03*
X498000Y1342985D03*
X510000Y1354485D03*
X522000D03*
X510000Y1364485D03*
X522000D03*
X510000Y1374485D03*
Y1384485D03*
X522000Y1374485D03*
Y1384485D03*
X498000Y1382985D03*
Y1372985D03*
X486000Y1382985D03*
Y1372985D03*
X498000Y1362985D03*
X486000D03*
X658200Y1329200D03*
X666100D03*
X581800Y1321200D03*
Y1329100D03*
X589700D03*
Y1321200D03*
X594800Y1313500D03*
X597600Y1321200D03*
Y1329100D03*
X610600Y1313500D03*
Y1305600D03*
Y1297600D03*
X602700Y1313500D03*
Y1305600D03*
Y1297600D03*
X629200Y1329100D03*
X605500Y1321200D03*
X613400D03*
X605500Y1329100D03*
X613400D03*
X621300D03*
X666100Y1360800D03*
Y1368700D03*
Y1376600D03*
Y1352900D03*
X658200Y1360800D03*
Y1368700D03*
Y1376600D03*
Y1352900D03*
X666100Y1337100D03*
Y1345000D03*
X658200Y1337100D03*
Y1345000D03*
X581800Y1376500D03*
Y1384400D03*
Y1392300D03*
Y1360700D03*
Y1368600D03*
Y1352800D03*
Y1344900D03*
Y1337000D03*
X589700Y1392300D03*
Y1400200D03*
Y1344900D03*
Y1352800D03*
Y1384400D03*
Y1376500D03*
Y1368600D03*
Y1360700D03*
Y1337000D03*
X597600Y1400200D03*
Y1408100D03*
Y1360700D03*
Y1368600D03*
Y1392300D03*
Y1376500D03*
Y1384400D03*
Y1352800D03*
Y1337000D03*
Y1344900D03*
X629200D03*
X621300D03*
X613400D03*
X605500D03*
Y1360700D03*
X613400D03*
X621300D03*
X629200D03*
X605500Y1352800D03*
X613400D03*
X621300D03*
X629200D03*
Y1368600D03*
Y1376500D03*
X605500Y1408100D03*
Y1400200D03*
Y1392300D03*
Y1384400D03*
Y1376500D03*
Y1368600D03*
X613400Y1400200D03*
Y1392300D03*
Y1384400D03*
Y1376500D03*
Y1368600D03*
X621300Y1376500D03*
Y1368600D03*
X629200Y1337000D03*
X613400D03*
X621300D03*
X605500D03*
X613400Y1408100D03*
X705600Y1329200D03*
X697700Y1321300D03*
Y1329200D03*
X689800D03*
Y1321300D03*
X693800Y1313900D03*
Y1306000D03*
X685900D03*
X678000D03*
Y1313900D03*
X685900D03*
X681900Y1321300D03*
X674000D03*
Y1329200D03*
X681900D03*
X693800Y1298000D03*
X685900D03*
X678000D03*
X768867Y1311110D03*
Y1335110D03*
Y1327110D03*
Y1319110D03*
X705600Y1337100D03*
Y1360800D03*
Y1352900D03*
Y1345000D03*
Y1376600D03*
Y1368700D03*
X699600Y1408200D03*
Y1392400D03*
Y1400300D03*
X697700Y1345000D03*
Y1360800D03*
Y1368700D03*
Y1376600D03*
X697100Y1384600D03*
X697700Y1352900D03*
Y1337100D03*
X691700Y1408200D03*
Y1400300D03*
X675900D03*
X683800D03*
Y1408200D03*
X675900D03*
X689800Y1352900D03*
Y1384500D03*
Y1376600D03*
X691700Y1392400D03*
X689800Y1368700D03*
Y1360800D03*
X674000D03*
X681900D03*
Y1368700D03*
X674000D03*
X675900Y1392400D03*
X683800D03*
X674000Y1376600D03*
X681900D03*
Y1384500D03*
X674000D03*
Y1352900D03*
X681900D03*
X689800Y1345000D03*
Y1337100D03*
X681900D03*
X674000D03*
X681900Y1345000D03*
X674000D03*
X768867Y1383110D03*
Y1359110D03*
Y1367110D03*
Y1351110D03*
Y1343110D03*
Y1391110D03*
Y1399110D03*
Y1375110D03*
X786200Y1334100D03*
X794200D03*
X801000Y1333800D03*
X786200Y1326100D03*
X794200D03*
X776867Y1311110D03*
Y1335110D03*
Y1327110D03*
Y1319110D03*
X775600Y1302400D03*
X801000Y1325800D03*
X790056Y1297863D03*
X798056D03*
X782056D03*
X834000Y1324500D03*
Y1317500D03*
Y1310500D03*
Y1303500D03*
X827000D03*
X820000D03*
X827000Y1310500D03*
X820000D03*
X827000Y1317500D03*
X820000D03*
X827000Y1324500D03*
X820000D03*
X776867Y1399110D03*
X790330Y1407929D03*
X782330D03*
X798330D03*
X795000Y1377900D03*
X786600Y1378100D03*
X790950Y1372703D03*
X776867Y1383110D03*
Y1359110D03*
X782950Y1372703D03*
X776867Y1367110D03*
Y1375110D03*
X798950Y1372703D03*
X776867Y1391110D03*
X790223Y1339930D03*
X782223Y1339430D03*
X798223Y1339930D03*
X776867Y1351110D03*
Y1343110D03*
X834000Y1386000D03*
Y1379000D03*
Y1363000D03*
Y1356000D03*
Y1349000D03*
Y1342000D03*
X827000D03*
X820000D03*
X827000Y1349000D03*
X820000D03*
X827000Y1356000D03*
X820000D03*
X827000Y1363000D03*
X820000D03*
X827000Y1379000D03*
X820000D03*
X827000Y1386000D03*
X820000D03*
X827000Y1393000D03*
X820000D03*
X958200Y1303900D03*
X942400D03*
X950300D03*
X934500D03*
X926600D03*
X958200Y1311800D03*
X926600D03*
X934500D03*
X950300D03*
X942400D03*
X903500Y1319400D03*
X950300Y1319700D03*
X958200D03*
X934500D03*
X942400D03*
X926600D03*
X918700D03*
X910800D03*
X887800Y1327100D03*
X934700Y1327500D03*
X895200D03*
X903100D03*
X911000D03*
X926800D03*
X918900D03*
X887800Y1335000D03*
X886400Y1368100D03*
Y1376000D03*
X894300D03*
Y1368100D03*
X934700Y1335400D03*
X926800D03*
X918900D03*
X895200D03*
X903100D03*
X911000D03*
X890400Y1358900D03*
X887800Y1350800D03*
Y1342900D03*
X937300Y1359300D03*
X934700Y1343300D03*
Y1351200D03*
X926800Y1343300D03*
Y1351200D03*
X929400Y1359300D03*
X918900Y1343300D03*
Y1351200D03*
X921500Y1359300D03*
X918000Y1368100D03*
Y1376000D03*
X910100Y1368100D03*
Y1376000D03*
X911000Y1343300D03*
Y1351200D03*
X913600Y1359300D03*
X903100Y1343300D03*
Y1351200D03*
X905700Y1359300D03*
X902200Y1376000D03*
Y1368100D03*
X897800Y1359300D03*
X895200Y1351200D03*
Y1343300D03*
X998600Y1300900D03*
X991500Y1312100D03*
X1020800Y1300400D03*
X991455Y1320416D03*
X996400Y1315900D03*
X996200Y1307800D03*
X1014000Y1300600D03*
X991755Y1327716D03*
X996055Y1324116D03*
X1007100Y1301100D03*
X1011100Y1305300D03*
X1019829Y1306139D03*
X1002700Y1305700D03*
X991800Y1303400D03*
X1000200Y1311700D03*
Y1320500D03*
X1016429Y1333939D03*
X1021829D03*
X1011029D03*
X1005629D03*
X986755Y1323816D03*
X986700Y1307600D03*
X1000200Y1328100D03*
X1050818Y1311189D03*
Y1316589D03*
X1045418Y1321989D03*
X1050818D03*
X1034618Y1311189D03*
X1040018D03*
X1045418D03*
X1040018Y1316589D03*
X1034618D03*
X1040018Y1321989D03*
X1031600Y1335100D03*
X1037200Y1335000D03*
X1034618Y1321989D03*
X997900Y1335800D03*
X992500D03*
X997900Y1341200D03*
X992500D03*
X997900Y1346600D03*
X992500D03*
X997900Y1352000D03*
X992500D03*
Y1357400D03*
X997900D03*
X989083Y1387764D03*
X989509Y1393422D03*
X994700Y1385000D03*
X999700Y1374500D03*
X989100Y1381700D03*
X994200Y1362700D03*
X1019829Y1389539D03*
X1013692Y1389688D03*
X1019829Y1361739D03*
X1014306Y1361710D03*
X1008870Y1361681D03*
X1003367Y1361655D03*
X1004217Y1389394D03*
X1008298Y1393071D03*
X994400Y1377300D03*
X999930Y1393070D03*
X999800Y1381600D03*
X999900Y1366800D03*
X994300Y1370100D03*
X989200Y1374800D03*
X988900Y1366900D03*
X1034600Y1349600D03*
X1042400Y1349500D03*
X1037540Y1344964D03*
X1034799Y1340183D03*
X1044700Y1335500D03*
X1043300Y1342500D03*
X1048000Y1346100D03*
X1037111Y1372380D03*
X1039988Y1367352D03*
X1044400Y1363100D03*
X1036900Y1362600D03*
X1034380Y1367469D03*
X1031300Y1362700D03*
X1042100Y1377100D03*
X1034300Y1377200D03*
X1047401Y1375084D03*
X1066481Y1327759D03*
X1061081D03*
X1066481Y1333159D03*
X1061081D03*
X1061618Y1316589D03*
X1056218Y1311189D03*
X1061618D03*
X1056218Y1316589D03*
X1060218Y1321989D03*
X1066491Y1319983D03*
X1066407Y1313972D03*
X1066481Y1338559D03*
X1061081D03*
X1066481Y1343959D03*
X1061081D03*
X1066481Y1376359D03*
Y1349359D03*
Y1354759D03*
Y1360159D03*
Y1365559D03*
Y1370959D03*
X1061081Y1376359D03*
Y1370959D03*
Y1365559D03*
Y1360159D03*
Y1354759D03*
Y1349359D03*
G54D65*
X113314Y1452450D03*
X115874D03*
X118434D03*
Y1458950D03*
X113314D03*
X741572Y1438184D03*
X744132D03*
X746692D03*
Y1444684D03*
X741572D03*
X1030003Y1444649D03*
X1027443D03*
X1024883D03*
Y1438149D03*
X1030003D03*
X1259614Y1457550D03*
X1262174D03*
X1264734D03*
Y1464050D03*
X1259614D03*
X1796666Y1456950D03*
X1799226D03*
X1801786D03*
Y1463450D03*
X1796666D03*
G54D38*
X72049Y260355D03*
X68109D03*
X72049Y254605D03*
X68109D03*
X72049Y713111D03*
X68109D03*
X72049Y707361D03*
X68109D03*
X192321Y260355D03*
Y254605D03*
Y713111D03*
Y707361D03*
X196261Y260355D03*
Y254605D03*
Y713111D03*
Y707361D03*
X320474Y260355D03*
X316534D03*
X320474Y254605D03*
X316534D03*
X320474Y713111D03*
X316534D03*
X320474Y707361D03*
X316534D03*
X444687Y260355D03*
X440747D03*
X444687Y254605D03*
X440747D03*
X444687Y713111D03*
X440747D03*
X444687Y707361D03*
X440747D03*
X568899Y260355D03*
X564959D03*
X568899Y254605D03*
X564959D03*
X568899Y713111D03*
X564959D03*
X568899Y707361D03*
X564959D03*
X693112Y260355D03*
X689172D03*
X693112Y254605D03*
X689172D03*
X693112Y713111D03*
X689172D03*
X693112Y707361D03*
X689172D03*
X1242718Y260355D03*
X1238778D03*
X1242718Y254605D03*
X1238778D03*
X1242718Y713111D03*
X1238778D03*
X1242718Y707361D03*
X1238778D03*
X1366931Y260355D03*
X1362991D03*
X1366931Y254605D03*
X1362991D03*
X1366931Y713111D03*
X1362991D03*
X1366931Y707361D03*
X1362991D03*
X1491143Y260355D03*
X1487203D03*
X1491143Y254605D03*
X1487203D03*
X1491143Y713111D03*
X1487203D03*
X1491143Y707361D03*
X1487203D03*
X1615356Y260355D03*
X1611416D03*
X1615356Y254605D03*
X1611416D03*
X1615356Y713111D03*
X1611416D03*
X1615356Y707361D03*
X1611416D03*
X1739568Y260355D03*
X1735628D03*
X1739568Y254605D03*
X1735628D03*
X1739568Y713111D03*
X1735628D03*
X1739568Y707361D03*
X1735628D03*
X1863781Y260355D03*
X1859841D03*
X1863781Y254605D03*
X1859841D03*
X1863781Y713111D03*
X1859841D03*
X1863781Y707361D03*
X1859841D03*
G54D74*
X503248Y715748D03*
X1673917Y262992D03*
G54D83*
X683110Y1463550D03*
X696890D03*
Y1443450D03*
X683110D03*
X990553Y1451449D03*
X1004333D03*
Y1431349D03*
X990553D03*
G54D92*
X959913Y519617D03*
Y522177D03*
Y524737D03*
Y527297D03*
X978571Y553411D03*
Y550851D03*
Y548291D03*
Y545731D03*
X962271D03*
Y548291D03*
Y550851D03*
Y553411D03*
X976213Y527297D03*
Y524737D03*
Y522177D03*
Y519617D03*
G54D56*
X127600Y122600D03*
X158474Y1419300D03*
X153374Y1453700D03*
Y1435200D03*
X250900Y122800D03*
X375500D03*
X440849Y115300D03*
X499900Y122700D03*
X624000D03*
X668000Y1422200D03*
X672500Y1476200D03*
X748200Y575500D03*
X698500Y1422200D03*
X685000D03*
X693000D03*
X735232Y1443534D03*
X990100Y829700D03*
X1026515Y883181D03*
X1000443Y1410099D03*
X992443D03*
X975443Y1411099D03*
X1005943Y1410099D03*
X1035943Y1428099D03*
X971438Y1450108D03*
X1207440Y1421054D03*
X1266600Y122800D03*
Y575500D03*
X1266400Y1028200D03*
X1300374Y1453700D03*
Y1435200D03*
X1253374Y1463100D03*
X1391200Y122800D03*
X1390400Y575500D03*
X1391000Y1028300D03*
X1515400Y122800D03*
X1515200Y575500D03*
X1515400Y1028300D03*
X1639300Y122800D03*
X1638200Y575500D03*
X1639100Y1028300D03*
X1680626Y1453700D03*
Y1435200D03*
X1763600Y122800D03*
X1763300Y1028300D03*
X1790226Y1462300D03*
X1879800Y984700D03*
G54D29*
X60300Y100500D03*
Y553000D03*
Y1006000D03*
X184300Y553000D03*
X140800Y579000D03*
X111256Y878062D03*
X140800Y1032000D03*
X184800Y1006000D03*
X198800Y82500D03*
X209083Y440326D03*
X264800Y579000D03*
X264500Y1032000D03*
X226955Y1434029D03*
X308800Y100500D03*
Y553000D03*
Y1006000D03*
X432800Y553000D03*
X389300Y579000D03*
Y1032000D03*
X432800Y1006000D03*
X557300Y100500D03*
Y553000D03*
X513300Y579000D03*
Y1032000D03*
X557300Y1006000D03*
X637800Y579000D03*
Y1032000D03*
X695800Y82500D03*
X751800Y126500D03*
X681300Y553000D03*
Y1006000D03*
X753100Y1032000D03*
X695800Y1476000D03*
X714300Y1449700D03*
X840790Y645690D03*
X838500Y804500D03*
X870600Y774500D03*
X931300Y763820D03*
X871300Y887500D03*
X877000Y1188400D03*
X900100Y1191700D03*
X981681Y559671D03*
X980247Y533383D03*
X1011641Y895045D03*
X1021933Y892965D03*
X968100Y1193500D03*
X1334300Y113500D03*
X1335300Y566500D03*
Y1019000D03*
X1435800Y81000D03*
X1374029Y1434045D03*
X1459300Y113500D03*
Y566500D03*
Y1019000D03*
X1604700Y133000D03*
X1583800Y566500D03*
Y1019000D03*
X1683200Y81000D03*
X1707800Y113500D03*
Y566500D03*
Y1019000D03*
X1751852Y443744D03*
X1754174Y1434109D03*
X1881800Y81500D03*
X1866300Y82000D03*
X1867500Y42100D03*
X1830800Y113500D03*
X1831800Y566500D03*
X1879700Y534600D03*
X1851800Y553000D03*
X1826256Y878062D03*
X1831800Y1019000D03*
X1851800Y1006000D03*
G54D47*
X126709Y57719D03*
X128909D03*
X126709Y59919D03*
X128909D03*
X126709Y510475D03*
X128909D03*
X126709Y512675D03*
X128909D03*
X126709Y963231D03*
X128909D03*
X126709Y965431D03*
X128909D03*
X250921Y57719D03*
X253121D03*
X250921Y59919D03*
X253121D03*
X250921Y510475D03*
X253121D03*
X250921Y512675D03*
X253121D03*
X250921Y963231D03*
X253121D03*
X250921Y965431D03*
X253121D03*
X375134Y57719D03*
X377334D03*
X375134Y59919D03*
X377334D03*
X375134Y510475D03*
X377334D03*
X375134Y512675D03*
X377334D03*
X375134Y963231D03*
X377334D03*
X375134Y965431D03*
X377334D03*
X499346Y57719D03*
X501546D03*
X499346Y59919D03*
X501546D03*
X499346Y510475D03*
X501546D03*
X499346Y512675D03*
X501546D03*
X499346Y963231D03*
X501546D03*
X499346Y965431D03*
X501546D03*
X623559Y57719D03*
X625759D03*
X623559Y59919D03*
X625759D03*
X623559Y510475D03*
X625759D03*
X623559Y512675D03*
X625759D03*
X623559Y965431D03*
X625759D03*
X623559Y963231D03*
X625759D03*
X747772Y57719D03*
X749972D03*
X747772Y59919D03*
X749972D03*
X747772Y510475D03*
X749972D03*
X747772Y512675D03*
X749972D03*
X747772Y965431D03*
X749972D03*
X747772Y963231D03*
X749972D03*
G54D57*
X131200Y262981D03*
Y715737D03*
Y1168492D03*
X379232Y262981D03*
Y715737D03*
Y1168492D03*
X627263Y262981D03*
Y715737D03*
Y1168492D03*
X747244Y381878D03*
Y814949D03*
X961417Y703925D03*
Y972429D03*
X1181889Y381878D03*
Y972429D03*
X1301870Y262980D03*
Y715737D03*
Y1168492D03*
X1549901Y262981D03*
Y715737D03*
Y1168492D03*
X1797933Y262980D03*
Y715737D03*
Y1168492D03*
G54D66*
X110639Y1486040D03*
Y1488600D03*
Y1491160D03*
X118709D03*
Y1488600D03*
Y1486040D03*
X736597Y1471974D03*
Y1474534D03*
Y1477094D03*
X744667D03*
Y1474534D03*
Y1471974D03*
X1256939Y1490840D03*
Y1493400D03*
Y1495960D03*
X1265009D03*
Y1493400D03*
Y1490840D03*
G54D84*
X685079Y1463250D03*
X687047D03*
X689016D03*
X690984D03*
X692953D03*
X694921D03*
Y1443750D03*
X692953D03*
X690984D03*
X689016D03*
X687047D03*
X685079D03*
X992522Y1451149D03*
X994490D03*
X996459D03*
X998427D03*
X1000396D03*
X1002364D03*
Y1431649D03*
X1000396D03*
X998427D03*
X996459D03*
X994490D03*
X992522D03*
G54D39*
X79567Y388546D03*
X84567D03*
X73500Y840700D03*
X68500D03*
X95263Y880325D03*
X193090Y442589D03*
X191000Y840700D03*
X196000D03*
X213200Y388200D03*
X218200D03*
X315500D03*
X320500D03*
X315500Y840700D03*
X320500D03*
X440000Y388200D03*
X445000D03*
Y840700D03*
X440000D03*
X564000Y388200D03*
X569000D03*
X564000Y840700D03*
X569000D03*
X651295Y1435619D03*
X680500Y388200D03*
X685500D03*
X680500Y840700D03*
X685500D03*
X676500Y1423700D03*
X958738Y1423518D03*
X998000Y1114200D03*
X983943Y1411599D03*
X1040127Y1426700D03*
X1243500Y383700D03*
X1238462Y836388D03*
X1243462D03*
X1248500Y383700D03*
X1362500Y387700D03*
X1367500D03*
X1377100Y573400D03*
X1362500Y841200D03*
X1367500D03*
X1376900Y1026000D03*
X1487000Y387700D03*
X1492000D03*
X1500800Y573000D03*
X1487000Y840700D03*
X1492000D03*
X1500700Y1026000D03*
X1611000Y387700D03*
X1616000D03*
X1625500Y573200D03*
X1611000Y840700D03*
X1616000D03*
X1625400Y1026100D03*
X1735859Y446007D03*
X1735000Y387700D03*
X1740000D03*
X1735000Y840700D03*
X1740000D03*
X1810263Y880325D03*
X1749300Y1026100D03*
X1832100Y388500D03*
X1827100D03*
X1876100Y515400D03*
X1859500Y840700D03*
X1864500D03*
X1867500Y982400D03*
G54D48*
X150500Y29300D03*
X143300Y594500D03*
Y1047500D03*
X144674Y1457000D03*
X267300Y594500D03*
X267000Y1047500D03*
X228174Y1430000D03*
X391800Y594500D03*
Y1047500D03*
X515800Y594500D03*
Y1047500D03*
X510300Y1465500D03*
X640300Y594500D03*
Y1047500D03*
X842290Y641690D03*
X840000Y800500D03*
X862658Y1392892D03*
X932800Y759320D03*
X872300Y892000D03*
X934300Y880000D03*
X984141Y563811D03*
X1010200Y1129300D03*
X1050500Y1417000D03*
X1043350Y1480314D03*
X1291674Y1457000D03*
X1375174Y1430000D03*
X1671926Y1457000D03*
X1817300Y28900D03*
X1755426Y1430000D03*
G54D93*
X903125Y758850D03*
X910875D03*
X907000Y766350D03*
X874000Y1205650D03*
X870125Y1198150D03*
X877875D03*
G54D75*
X537234Y1422529D03*
Y1434129D03*
G54D58*
X184874Y1416450D03*
X107474Y1458600D03*
X198800Y37400D03*
X440400Y35700D03*
X524211Y1429134D03*
X669761Y1453700D03*
X695600Y37300D03*
X834470Y937130D03*
X924000Y881700D03*
X951569Y1399632D03*
X950339Y1387003D03*
X1002118Y1464065D03*
X978443Y1441599D03*
X1125615Y1311270D03*
X1175800Y1309100D03*
X1208933Y1309144D03*
X1200962Y1405802D03*
X1324000Y1416450D03*
X1712126D03*
X1803100Y75000D03*
G54D85*
X690000Y1453500D03*
X997443Y1441399D03*
G54D76*
X517500Y1471924D03*
Y1458624D03*
X535200Y1447950D03*
Y1461250D03*
G54D67*
X217500Y51200D03*
X208500D03*
X466000Y51500D03*
X457000D03*
X714500Y51300D03*
X705500D03*
X1040500Y1410500D03*
X1049500D03*
X1323500Y527000D03*
X1332500D03*
X1323500Y979500D03*
X1332500D03*
X1447500Y74000D03*
X1456500D03*
X1447500Y527000D03*
X1456500D03*
X1447500Y979500D03*
X1456500D03*
X1572000Y527000D03*
X1581000D03*
X1572000Y979500D03*
X1581000D03*
X1696000Y74000D03*
X1705000D03*
X1696000Y527000D03*
X1705000D03*
X1696000Y979500D03*
X1705000D03*
X1818900Y94400D03*
X1827900D03*
X1820000Y527000D03*
X1829000D03*
X1820000Y979500D03*
X1829000D03*
G54D49*
X144900Y29300D03*
X137700Y594500D03*
Y1047500D03*
X139074Y1457000D03*
X261700Y594500D03*
X261400Y1047500D03*
X222574Y1430000D03*
X386200Y594500D03*
Y1047500D03*
X510200Y594500D03*
Y1047500D03*
X504700Y1465500D03*
X634700Y594500D03*
Y1047500D03*
X836690Y641690D03*
X834400Y800500D03*
X857058Y1392892D03*
X927200Y759320D03*
X866700Y892000D03*
X928700Y880000D03*
X978541Y563811D03*
X1004600Y1129300D03*
X1044900Y1417000D03*
X1037750Y1480314D03*
X1286074Y1457000D03*
X1369574Y1430000D03*
X1666326Y1457000D03*
X1811700Y28900D03*
X1749826Y1430000D03*
G54D94*
X949000Y1202776D03*
Y1204350D03*
Y1205925D03*
Y1207500D03*
Y1209075D03*
Y1210650D03*
Y1212224D03*
X965000D03*
Y1210650D03*
Y1209075D03*
Y1207500D03*
Y1205925D03*
Y1204350D03*
Y1202776D03*
X1116612Y1384049D03*
Y1385623D03*
Y1387198D03*
Y1388773D03*
Y1390348D03*
Y1391923D03*
Y1393497D03*
X1132612D03*
Y1391923D03*
Y1390348D03*
Y1388773D03*
Y1387198D03*
Y1385623D03*
Y1384049D03*
G54D59*
X184874Y1420050D03*
X107474Y1462200D03*
X198800Y41000D03*
X440400Y39300D03*
X524211Y1432734D03*
X669761Y1457300D03*
X695600Y40900D03*
X834470Y940730D03*
X924000Y885300D03*
X951569Y1403232D03*
X950339Y1390603D03*
X1002118Y1467665D03*
X978443Y1445199D03*
X1125615Y1314870D03*
X1175800Y1312700D03*
X1208933Y1312744D03*
X1200962Y1409402D03*
X1324000Y1420050D03*
X1712126D03*
X1803100Y78600D03*
G54D68*
X246535Y1320472D03*
X531535D03*
G54D95*
X957000Y1199500D03*
X955425D03*
X953850D03*
X952276D03*
Y1215500D03*
X953850D03*
X955425D03*
X957000D03*
X961724Y1199500D03*
X960150D03*
X958575D03*
Y1215500D03*
X960150D03*
X961724D03*
X1119888Y1396773D03*
X1121462D03*
X1123037D03*
X1124612D03*
X1126187D03*
X1127762D03*
X1129336D03*
Y1380773D03*
X1127762D03*
X1126187D03*
X1124612D03*
X1123037D03*
X1121462D03*
X1119888D03*
G54D77*
X627499Y1306804D03*
X659901D03*
Y1398896D03*
X627499D03*
X948099Y1340696D03*
X980501D03*
G54D86*
X685000Y1453500D03*
X690000Y1448500D03*
X695000Y1453500D03*
X690000Y1458500D03*
Y1453500D03*
X957000Y1207500D03*
X953100Y1211400D03*
X953000Y1203600D03*
X960900Y1211400D03*
Y1203600D03*
X992443Y1441399D03*
X1002443D03*
X997443Y1436399D03*
Y1446399D03*
Y1441399D03*
X1124612Y1388773D03*
G54D78*
X627499Y1290524D03*
X659901D03*
Y1415176D03*
X627499D03*
X948099Y1356976D03*
X980501D03*
G54D69*
X266535Y1320472D03*
X511535D03*
G54D96*
X934500Y1367958D03*
Y1396242D03*
G54D87*
X862205Y277953D03*
X848032D03*
X833859D03*
X862205Y272441D03*
X848032D03*
X833859D03*
X862205Y263779D03*
X848032D03*
X833859D03*
X862205Y258268D03*
X848032D03*
X833859D03*
X862205Y282283D03*
X848032D03*
X833859D03*
X862205Y268110D03*
X848032D03*
X833859D03*
X862205Y253937D03*
X848032D03*
X833859D03*
X855118Y282677D03*
X840945D03*
X826772D03*
X855118Y277165D03*
X840945D03*
X826772D03*
X855118Y272835D03*
X840945D03*
X826772D03*
X855118Y268504D03*
X840945D03*
X826772D03*
X855118Y262992D03*
X840945D03*
X826772D03*
X862205Y306299D03*
X848032D03*
X833859D03*
X862205Y300787D03*
X848032D03*
X833859D03*
X862205Y292126D03*
X848032D03*
X833859D03*
X862205Y286614D03*
X848032D03*
X833859D03*
X862205Y310630D03*
X848032D03*
X833859D03*
X862205Y296457D03*
X848032D03*
X833859D03*
X855118Y311023D03*
X840945D03*
X826772D03*
X855118Y305512D03*
X840945D03*
X826772D03*
X855118Y296850D03*
X840945D03*
X826772D03*
X855118Y291338D03*
X840945D03*
X826772D03*
X855118Y315354D03*
X840945D03*
X826772D03*
X855118Y301181D03*
X840945D03*
X826772D03*
X855118Y287008D03*
X840945D03*
X826772D03*
X904725Y272835D03*
Y277165D03*
Y282677D03*
X911811Y272441D03*
Y277953D03*
Y282283D03*
X904725Y262992D03*
Y268504D03*
X911811Y253937D03*
Y258268D03*
Y263779D03*
Y268110D03*
X897638Y282283D03*
Y272441D03*
Y277953D03*
Y253937D03*
Y268110D03*
Y258268D03*
Y263779D03*
X890552Y272835D03*
Y277165D03*
Y282677D03*
Y262992D03*
Y268504D03*
X876378Y277953D03*
Y272441D03*
Y263779D03*
Y258268D03*
Y282283D03*
Y268110D03*
Y253937D03*
X869292Y282677D03*
Y277165D03*
Y272835D03*
Y268504D03*
Y262992D03*
X904725Y305512D03*
Y311023D03*
Y315354D03*
X911811Y306299D03*
Y310630D03*
X904725Y301181D03*
X911811Y300787D03*
X904725Y287008D03*
Y291338D03*
Y296850D03*
X911811Y286614D03*
Y292126D03*
Y296457D03*
X897638Y310630D03*
Y306299D03*
Y296457D03*
Y286614D03*
Y292126D03*
Y300787D03*
X890552Y315354D03*
Y305512D03*
Y311023D03*
Y287008D03*
Y301181D03*
Y291338D03*
Y296850D03*
X876378Y306299D03*
Y300787D03*
Y292126D03*
Y286614D03*
Y310630D03*
Y296457D03*
X869292Y311023D03*
Y305512D03*
Y296850D03*
Y291338D03*
Y315354D03*
Y301181D03*
Y287008D03*
X1091089Y520057D03*
X1095420D03*
X1100932D03*
X1105262D03*
X1109593D03*
X1115105D03*
X1119435D03*
X1123766D03*
X1129278D03*
X1133609D03*
X1095026Y527143D03*
X1099357D03*
X1104869D03*
X1109199D03*
X1113530D03*
X1119042D03*
X1123372D03*
X1127703D03*
X1133215D03*
X1091089Y534230D03*
X1095420D03*
X1100932D03*
X1105262D03*
X1109593D03*
X1115105D03*
X1119435D03*
X1123766D03*
X1129278D03*
X1133609D03*
X1095026Y541317D03*
X1099357D03*
X1104869D03*
X1109199D03*
X1113530D03*
X1119042D03*
X1123372D03*
X1127703D03*
X1133215D03*
X1091089Y548403D03*
X1095420D03*
X1100932D03*
X1105262D03*
X1109593D03*
X1115105D03*
X1119435D03*
X1123766D03*
X1129278D03*
X1133609D03*
X1095026Y555490D03*
X1099357D03*
X1104869D03*
X1109199D03*
X1113530D03*
X1119042D03*
X1123372D03*
X1127703D03*
X1133215D03*
X1091089Y562576D03*
X1095420D03*
X1100932D03*
X1105262D03*
X1109593D03*
X1115105D03*
X1119435D03*
X1123766D03*
X1129278D03*
X1133609D03*
X1095026Y569663D03*
X1099357D03*
X1104869D03*
X1109199D03*
X1113530D03*
X1119042D03*
X1123372D03*
X1127703D03*
X1133215D03*
X1091089Y691711D03*
Y705884D03*
Y720057D03*
Y734230D03*
Y748403D03*
Y762577D03*
X1095420Y691711D03*
Y705884D03*
Y720057D03*
Y734230D03*
Y748403D03*
Y762577D03*
X1100932Y691711D03*
Y705884D03*
Y720057D03*
Y734230D03*
Y748403D03*
Y762577D03*
X1105262Y691711D03*
Y705884D03*
Y720057D03*
Y734230D03*
Y748403D03*
Y762577D03*
X1109593Y691711D03*
Y705884D03*
Y720057D03*
Y734230D03*
Y748403D03*
Y762577D03*
X1115105Y691711D03*
Y705884D03*
Y720057D03*
Y734230D03*
Y748403D03*
Y762577D03*
X1119435Y691711D03*
Y705884D03*
Y720057D03*
Y734230D03*
Y748403D03*
Y762577D03*
X1123766Y691711D03*
Y705884D03*
Y720057D03*
Y734230D03*
Y748403D03*
Y762577D03*
X1129278Y691711D03*
Y705884D03*
Y720057D03*
Y734230D03*
Y748403D03*
Y762577D03*
X1133609Y691711D03*
Y705884D03*
Y720057D03*
Y734230D03*
Y748403D03*
Y762577D03*
X1095026Y698797D03*
Y712970D03*
Y727144D03*
Y741317D03*
Y755490D03*
X1099357Y698797D03*
Y712970D03*
Y727144D03*
Y741317D03*
Y755490D03*
X1104869Y698797D03*
Y712970D03*
Y727144D03*
Y741317D03*
Y755490D03*
X1109199Y698797D03*
Y712970D03*
Y727144D03*
Y741317D03*
Y755490D03*
X1113530Y698797D03*
Y712970D03*
Y727144D03*
Y741317D03*
Y755490D03*
X1119042Y698797D03*
Y712970D03*
Y727144D03*
Y741317D03*
Y755490D03*
X1123372Y698797D03*
Y712970D03*
Y727144D03*
Y741317D03*
Y755490D03*
X1127703Y698797D03*
Y712970D03*
Y727144D03*
Y741317D03*
Y755490D03*
X1133215Y698797D03*
Y712970D03*
Y727144D03*
Y741317D03*
Y755490D03*
X1091089Y776750D03*
Y790923D03*
Y805096D03*
Y819270D03*
Y833443D03*
Y847616D03*
X1095420Y776750D03*
Y790923D03*
Y805096D03*
Y819270D03*
Y833443D03*
Y847616D03*
X1100932Y776750D03*
Y790923D03*
Y805096D03*
Y819270D03*
Y833443D03*
Y847616D03*
X1105262Y776750D03*
Y790923D03*
Y805096D03*
Y819270D03*
Y833443D03*
Y847616D03*
X1109593Y776750D03*
Y790923D03*
Y805096D03*
Y819270D03*
Y833443D03*
Y847616D03*
X1115105Y776750D03*
Y790923D03*
Y805096D03*
Y819270D03*
Y833443D03*
Y847616D03*
X1119435Y776750D03*
Y790923D03*
Y805096D03*
Y819270D03*
Y833443D03*
Y847616D03*
X1123766Y776750D03*
Y790923D03*
Y805096D03*
Y819270D03*
Y833443D03*
Y847616D03*
X1129278Y776750D03*
Y790923D03*
Y805096D03*
Y819270D03*
Y833443D03*
Y847616D03*
X1133609Y776750D03*
Y790923D03*
Y805096D03*
Y819270D03*
Y833443D03*
Y847616D03*
X1095026Y769663D03*
Y783836D03*
Y798010D03*
Y812183D03*
Y826356D03*
Y840529D03*
Y854703D03*
X1099357Y769663D03*
Y783836D03*
Y798010D03*
Y812183D03*
Y826356D03*
Y840529D03*
Y854703D03*
X1104869Y769663D03*
Y783836D03*
Y798010D03*
Y812183D03*
Y826356D03*
Y840529D03*
Y854703D03*
X1109199Y769663D03*
Y783836D03*
Y798010D03*
Y812183D03*
Y826356D03*
Y840529D03*
Y854703D03*
X1113530Y769663D03*
Y783836D03*
Y798010D03*
Y812183D03*
Y826356D03*
Y840529D03*
Y854703D03*
X1119042Y769663D03*
Y783836D03*
Y798010D03*
Y812183D03*
Y826356D03*
Y840529D03*
Y854703D03*
X1123372Y769663D03*
Y783836D03*
Y798010D03*
Y812183D03*
Y826356D03*
Y840529D03*
Y854703D03*
X1127703Y769663D03*
Y783836D03*
Y798010D03*
Y812183D03*
Y826356D03*
Y840529D03*
Y854703D03*
X1133215Y769663D03*
Y783836D03*
Y798010D03*
Y812183D03*
Y826356D03*
Y840529D03*
Y854703D03*
X1091089Y861789D03*
Y875962D03*
Y890136D03*
Y904309D03*
Y918482D03*
Y932655D03*
X1095420Y861789D03*
Y875962D03*
Y890136D03*
Y904309D03*
Y918482D03*
Y932655D03*
X1100932Y861789D03*
Y875962D03*
Y890136D03*
Y904309D03*
Y918482D03*
Y932655D03*
X1105262Y861789D03*
Y875962D03*
Y890136D03*
Y904309D03*
Y918482D03*
Y932655D03*
X1109593Y861789D03*
Y875962D03*
Y890136D03*
Y904309D03*
Y918482D03*
Y932655D03*
X1115105Y861789D03*
Y875962D03*
Y890136D03*
Y904309D03*
Y918482D03*
Y932655D03*
X1119435Y861789D03*
Y875962D03*
Y890136D03*
Y904309D03*
Y918482D03*
Y932655D03*
X1123766Y861789D03*
Y875962D03*
Y890136D03*
Y904309D03*
Y918482D03*
Y932655D03*
X1129278Y861789D03*
Y875962D03*
Y890136D03*
Y904309D03*
Y918482D03*
Y932655D03*
X1133609Y861789D03*
Y875962D03*
Y890136D03*
Y904309D03*
Y918482D03*
Y932655D03*
X1095026Y868876D03*
Y883049D03*
Y897222D03*
Y911396D03*
Y925569D03*
Y939742D03*
X1099357Y868876D03*
Y883049D03*
Y897222D03*
Y911396D03*
Y925569D03*
Y939742D03*
X1104869Y868876D03*
Y883049D03*
Y897222D03*
Y911396D03*
Y925569D03*
Y939742D03*
X1109199Y868876D03*
Y883049D03*
Y897222D03*
Y911396D03*
Y925569D03*
Y939742D03*
X1113530Y868876D03*
Y883049D03*
Y897222D03*
Y911396D03*
Y925569D03*
Y939742D03*
X1119042Y868876D03*
Y883049D03*
Y897222D03*
Y911396D03*
Y925569D03*
Y939742D03*
X1123372Y868876D03*
Y883049D03*
Y897222D03*
Y911396D03*
Y925569D03*
Y939742D03*
X1127703Y868876D03*
Y883049D03*
Y897222D03*
Y911396D03*
Y925569D03*
Y939742D03*
X1133215Y868876D03*
Y883049D03*
Y897222D03*
Y911396D03*
Y925569D03*
Y939742D03*
G54D97*
X974015Y284449D03*
X986614D03*
X1002362D03*
X1014960D03*
X1030709D03*
X1043307D03*
X974015Y261812D03*
X986614D03*
X1002362D03*
X1014960D03*
X1030709D03*
X1043307D03*
X974015Y307087D03*
X986614D03*
X1002362D03*
X1014960D03*
X1030709D03*
X1043307D03*
G54D79*
X646102Y1321750D03*
X641102D03*
X646200Y1420576D03*
X641200D03*
X665700Y1463500D03*
Y1468500D03*
Y1458000D03*
Y1453000D03*
X858500Y845700D03*
X858100Y850000D03*
X848300Y847700D03*
X844800Y895902D03*
X845732Y891713D03*
X941559Y1408198D03*
Y1403198D03*
X966985Y1393900D03*
X961857D03*
X1130800Y472900D03*
X1156110Y473330D03*
X1152600Y468470D03*
X1177350Y597792D03*
G54D88*
X814843Y403862D03*
Y424130D03*
X810400Y561866D03*
Y582134D03*
X801300Y1201766D03*
Y1222034D03*
X1028394Y771349D03*
Y791617D03*
X1112677Y402838D03*
Y423106D03*
X1121600Y1201266D03*
Y1221534D03*
G54D89*
X859590Y650110D03*
Y652670D03*
Y655230D03*
Y657790D03*
Y660350D03*
Y662910D03*
Y665470D03*
X837390D03*
Y662910D03*
Y660350D03*
Y657790D03*
Y655230D03*
Y652670D03*
Y650110D03*
X833200Y760280D03*
Y757720D03*
Y755160D03*
Y752600D03*
Y750040D03*
Y747480D03*
Y744920D03*
X855400D03*
Y747480D03*
Y750040D03*
Y752600D03*
Y755160D03*
Y757720D03*
Y760280D03*
X859590Y668030D03*
Y670590D03*
Y673150D03*
Y675710D03*
Y678270D03*
X837390D03*
Y675710D03*
Y673150D03*
Y670590D03*
Y668030D03*
X838400Y856920D03*
X860600D03*
X833200Y773080D03*
Y770520D03*
Y767960D03*
Y765400D03*
Y762840D03*
X855400D03*
Y765400D03*
Y767960D03*
Y770520D03*
Y773080D03*
X861100Y809920D03*
Y812480D03*
Y815040D03*
Y817600D03*
Y820160D03*
Y822720D03*
Y825280D03*
Y827840D03*
Y830400D03*
Y832960D03*
Y835520D03*
Y838080D03*
X838900D03*
Y835520D03*
Y832960D03*
Y830400D03*
Y827840D03*
Y825280D03*
Y822720D03*
Y820160D03*
Y817600D03*
Y815040D03*
Y812480D03*
Y809920D03*
X838400Y885080D03*
Y882520D03*
Y879960D03*
Y877400D03*
Y874840D03*
Y872280D03*
Y869720D03*
Y867160D03*
Y864600D03*
Y862040D03*
Y859480D03*
X860600D03*
Y862040D03*
Y864600D03*
Y867160D03*
Y869720D03*
Y872280D03*
Y874840D03*
Y877400D03*
Y879960D03*
Y882520D03*
Y885080D03*
X947600Y769720D03*
Y772280D03*
Y774840D03*
Y777400D03*
Y779960D03*
Y782520D03*
Y785080D03*
Y787640D03*
Y790200D03*
Y792760D03*
Y795320D03*
Y797880D03*
X925400D03*
Y795320D03*
Y792760D03*
Y790200D03*
Y787640D03*
Y785080D03*
Y782520D03*
Y779960D03*
Y777400D03*
Y774840D03*
Y772280D03*
Y769720D03*
X898400Y1195980D03*
Y1198540D03*
Y1201100D03*
Y1203660D03*
Y1206220D03*
Y1208780D03*
Y1211340D03*
Y1213900D03*
Y1216460D03*
Y1219020D03*
X920600D03*
Y1216460D03*
Y1213900D03*
Y1211340D03*
Y1208780D03*
Y1206220D03*
Y1203660D03*
Y1201100D03*
Y1198540D03*
Y1195980D03*
X1116100Y1307375D03*
Y1304820D03*
Y1302260D03*
Y1299700D03*
Y1297140D03*
Y1294580D03*
Y1292025D03*
X1093900D03*
Y1294580D03*
Y1297140D03*
Y1299700D03*
Y1302260D03*
Y1304820D03*
Y1307375D03*
X1200912Y1399993D03*
Y1397433D03*
Y1394873D03*
Y1392313D03*
Y1389753D03*
Y1387193D03*
Y1384633D03*
Y1382073D03*
Y1379513D03*
Y1376953D03*
X1178712D03*
Y1379513D03*
Y1382073D03*
Y1384633D03*
Y1387193D03*
Y1389753D03*
Y1392313D03*
Y1394873D03*
Y1397433D03*
Y1399993D03*
G54D98*
X974015Y278544D03*
X1002362D03*
X1030709D03*
X974015Y267717D03*
X1002362D03*
X1030709D03*
X974015Y255906D03*
X1002362D03*
X1030709D03*
X986614Y278544D03*
X1014960D03*
X1043307D03*
X986614Y267717D03*
X1014960D03*
X1043307D03*
X986614Y255906D03*
X1014960D03*
X1043307D03*
X974015Y312993D03*
X1002362D03*
X1030709D03*
X974015Y301182D03*
X1002362D03*
X1030709D03*
X974015Y290355D03*
X1002362D03*
X1030709D03*
X986614Y312993D03*
X1014960D03*
X1043307D03*
X986614Y301182D03*
X1014960D03*
X1043307D03*
X986614Y290355D03*
X1014960D03*
X1043307D03*
X1101405Y1120040D03*
X1119633D03*
X1101405Y1132638D03*
X1119633D03*
G54D99*
X1042147Y379090D03*
X1066947D03*
M02*
